FILE_TYPE = MACRO_DRAWING;
SET COLOR_WIRE YELLOW;
SET COLOR_PROP MONO;
SET COLOR_DOT WHITE;
SET COLOR_ARC YELLOW;
SET COLOR_BODY GREEN;
SET COLOR_NOTE MONO;
SET PROP_DISPLAY VALUE;
SET PAGE_NUMBER P54;
FORCEADD OFFPAGE..3
(1575 5200);
FORCEPROP 2 LAST $XR0 28 
J 0
(1789 5200);
DISPLAY 0.638298 (1789 5200);
PAINT MONO (1789 5200);
FORCEPROP 2 LAST $XR1 53 
J 0
(1879 5200);
DISPLAY 0.638298 (1879 5200);
PAINT MONO (1879 5200);
FORCEPROP 2 LAST CDS_LIB mstr_standard
J 0
(1575 5200);
DISPLAY 0.787234 (1575 5200);
PAINT MONO (1575 5200);
DISPLAY INVISIBLE (1575 5200);
FORCEPROP 1 LAST OFFPAGE TRUE
J 0
(1900 5075);
DISPLAY 0.936170 (1900 5075);
PAINT GREEN (1900 5075);
DISPLAY INVISIBLE (1900 5075);
FORCEPROP 1 LAST COMMENT_BODY TRUE
J 0
(1525 5100);
DISPLAY 0.936170 (1525 5100);
PAINT GREEN (1525 5100);
DISPLAY INVISIBLE (1525 5100);
FORCEPROP 2 LAST PATH I1
J 0
(1775 5275);
DISPLAY 0.787234 (1775 5275);
PAINT MONO (1775 5275);
DISPLAY INVISIBLE (1775 5275);
FORCEADD TAP..6
R 2
(700 4850);
FORCEPROP 3 LASTPIN (650 4850) SIG_NAME M_F_DQS_DP<14>
J 0
(660 4860);
DISPLAY 0.659574 (660 4860);
PAINT MONO (660 4860);
DISPLAY INVISIBLE (660 4860);
FORCEPROP 1 LASTPIN (650 4850) BN 14
J 2
(700 4860);
DISPLAY 0.617021 (700 4860);
PAINT PINK (700 4860);
FORCEPROP 2 LAST CDS_LIB mstr_standard
J 0
(700 4850);
DISPLAY 0.787234 (700 4850);
PAINT MONO (700 4850);
DISPLAY INVISIBLE (700 4850);
FORCEPROP 1 LAST BODY_TYPE PLUMBING
J 2
(700 4800);
DISPLAY 1.234043 (700 4800);
PAINT GREEN (700 4800);
DISPLAY INVISIBLE (700 4800);
FORCEPROP 1 LAST HDL_TAP TRUE
J 2
(375 4725);
DISPLAY 1.234043 (375 4725);
PAINT GREEN (375 4725);
DISPLAY INVISIBLE (375 4725);
FORCEPROP 1 LAST PATH I10
J 2
(700 4850);
DISPLAY 0.936170 (700 4850);
PAINT GREEN (700 4850);
DISPLAY INVISIBLE (700 4850);
FORCEADD TAP..6
R 2
(-1650 2050);
FORCEPROP 3 LASTPIN (-1700 2050) SIG_NAME M_F_DQ<9>
J 0
(-1690 2060);
DISPLAY 0.659574 (-1690 2060);
PAINT MONO (-1690 2060);
DISPLAY INVISIBLE (-1690 2060);
FORCEPROP 1 LASTPIN (-1700 2050) BN 9
J 2
(-1650 2060);
DISPLAY 0.617021 (-1650 2060);
PAINT PINK (-1650 2060);
FORCEPROP 2 LAST CDS_LIB mstr_standard
J 2
(-1650 2050);
DISPLAY 0.787234 (-1650 2050);
PAINT MONO (-1650 2050);
DISPLAY INVISIBLE (-1650 2050);
FORCEPROP 1 LAST BODY_TYPE PLUMBING
J 2
(-1650 2000);
DISPLAY 1.234043 (-1650 2000);
PAINT GREEN (-1650 2000);
DISPLAY INVISIBLE (-1650 2000);
FORCEPROP 1 LAST HDL_TAP TRUE
J 2
(-1975 1925);
DISPLAY 1.234043 (-1975 1925);
PAINT GREEN (-1975 1925);
DISPLAY INVISIBLE (-1975 1925);
FORCEPROP 1 LAST PATH I100
J 2
(-1650 2050);
DISPLAY 0.936170 (-1650 2050);
PAINT GREEN (-1650 2050);
DISPLAY INVISIBLE (-1650 2050);
FORCEADD TAP..6
R 2
(-1650 2100);
FORCEPROP 3 LASTPIN (-1700 2100) SIG_NAME M_F_DQ<10>
J 0
(-1690 2110);
DISPLAY 0.659574 (-1690 2110);
PAINT MONO (-1690 2110);
DISPLAY INVISIBLE (-1690 2110);
FORCEPROP 1 LASTPIN (-1700 2100) BN 10
J 2
(-1650 2110);
DISPLAY 0.617021 (-1650 2110);
PAINT PINK (-1650 2110);
FORCEPROP 2 LAST CDS_LIB mstr_standard
J 2
(-1650 2100);
DISPLAY 0.787234 (-1650 2100);
PAINT MONO (-1650 2100);
DISPLAY INVISIBLE (-1650 2100);
FORCEPROP 1 LAST BODY_TYPE PLUMBING
J 2
(-1650 2050);
DISPLAY 1.234043 (-1650 2050);
PAINT GREEN (-1650 2050);
DISPLAY INVISIBLE (-1650 2050);
FORCEPROP 1 LAST HDL_TAP TRUE
J 2
(-1975 1975);
DISPLAY 1.234043 (-1975 1975);
PAINT GREEN (-1975 1975);
DISPLAY INVISIBLE (-1975 1975);
FORCEPROP 1 LAST PATH I101
J 2
(-1650 2100);
DISPLAY 0.936170 (-1650 2100);
PAINT GREEN (-1650 2100);
DISPLAY INVISIBLE (-1650 2100);
FORCEADD TAP..6
R 2
(-1650 1800);
FORCEPROP 3 LASTPIN (-1700 1800) SIG_NAME M_F_DQ<4>
J 0
(-1690 1810);
DISPLAY 0.659574 (-1690 1810);
PAINT MONO (-1690 1810);
DISPLAY INVISIBLE (-1690 1810);
FORCEPROP 1 LASTPIN (-1700 1800) BN 4
J 2
(-1650 1810);
DISPLAY 0.617021 (-1650 1810);
PAINT PINK (-1650 1810);
FORCEPROP 2 LAST CDS_LIB mstr_standard
J 2
(-1650 1800);
DISPLAY 0.787234 (-1650 1800);
PAINT MONO (-1650 1800);
DISPLAY INVISIBLE (-1650 1800);
FORCEPROP 1 LAST BODY_TYPE PLUMBING
J 2
(-1650 1750);
DISPLAY 1.234043 (-1650 1750);
PAINT GREEN (-1650 1750);
DISPLAY INVISIBLE (-1650 1750);
FORCEPROP 1 LAST HDL_TAP TRUE
J 2
(-1975 1675);
DISPLAY 1.234043 (-1975 1675);
PAINT GREEN (-1975 1675);
DISPLAY INVISIBLE (-1975 1675);
FORCEPROP 1 LAST PATH I102
J 2
(-1650 1800);
DISPLAY 0.936170 (-1650 1800);
PAINT GREEN (-1650 1800);
DISPLAY INVISIBLE (-1650 1800);
FORCEADD TAP..6
R 2
(-1650 1750);
FORCEPROP 3 LASTPIN (-1700 1750) SIG_NAME M_F_DQ<3>
J 0
(-1690 1760);
DISPLAY 0.659574 (-1690 1760);
PAINT MONO (-1690 1760);
DISPLAY INVISIBLE (-1690 1760);
FORCEPROP 1 LASTPIN (-1700 1750) BN 3
J 2
(-1650 1760);
DISPLAY 0.617021 (-1650 1760);
PAINT PINK (-1650 1760);
FORCEPROP 2 LAST CDS_LIB mstr_standard
J 2
(-1650 1750);
DISPLAY 0.787234 (-1650 1750);
PAINT MONO (-1650 1750);
DISPLAY INVISIBLE (-1650 1750);
FORCEPROP 1 LAST BODY_TYPE PLUMBING
J 2
(-1650 1700);
DISPLAY 1.234043 (-1650 1700);
PAINT GREEN (-1650 1700);
DISPLAY INVISIBLE (-1650 1700);
FORCEPROP 1 LAST HDL_TAP TRUE
J 2
(-1975 1625);
DISPLAY 1.234043 (-1975 1625);
PAINT GREEN (-1975 1625);
DISPLAY INVISIBLE (-1975 1625);
FORCEPROP 1 LAST PATH I103
J 2
(-1650 1750);
DISPLAY 0.936170 (-1650 1750);
PAINT GREEN (-1650 1750);
DISPLAY INVISIBLE (-1650 1750);
FORCEADD TAP..6
R 2
(-1650 1850);
FORCEPROP 3 LASTPIN (-1700 1850) SIG_NAME M_F_DQ<5>
J 0
(-1690 1860);
DISPLAY 0.659574 (-1690 1860);
PAINT MONO (-1690 1860);
DISPLAY INVISIBLE (-1690 1860);
FORCEPROP 1 LASTPIN (-1700 1850) BN 5
J 2
(-1650 1860);
DISPLAY 0.617021 (-1650 1860);
PAINT PINK (-1650 1860);
FORCEPROP 2 LAST CDS_LIB mstr_standard
J 2
(-1650 1850);
DISPLAY 0.787234 (-1650 1850);
PAINT MONO (-1650 1850);
DISPLAY INVISIBLE (-1650 1850);
FORCEPROP 1 LAST BODY_TYPE PLUMBING
J 2
(-1650 1800);
DISPLAY 1.234043 (-1650 1800);
PAINT GREEN (-1650 1800);
DISPLAY INVISIBLE (-1650 1800);
FORCEPROP 1 LAST HDL_TAP TRUE
J 2
(-1975 1725);
DISPLAY 1.234043 (-1975 1725);
PAINT GREEN (-1975 1725);
DISPLAY INVISIBLE (-1975 1725);
FORCEPROP 1 LAST PATH I104
J 2
(-1650 1850);
DISPLAY 0.936170 (-1650 1850);
PAINT GREEN (-1650 1850);
DISPLAY INVISIBLE (-1650 1850);
FORCEADD TAP..6
R 2
(-1650 1900);
FORCEPROP 3 LASTPIN (-1700 1900) SIG_NAME M_F_DQ<6>
J 0
(-1690 1910);
DISPLAY 0.659574 (-1690 1910);
PAINT MONO (-1690 1910);
DISPLAY INVISIBLE (-1690 1910);
FORCEPROP 1 LASTPIN (-1700 1900) BN 6
J 2
(-1650 1910);
DISPLAY 0.617021 (-1650 1910);
PAINT PINK (-1650 1910);
FORCEPROP 2 LAST CDS_LIB mstr_standard
J 2
(-1650 1900);
DISPLAY 0.787234 (-1650 1900);
PAINT MONO (-1650 1900);
DISPLAY INVISIBLE (-1650 1900);
FORCEPROP 1 LAST BODY_TYPE PLUMBING
J 2
(-1650 1850);
DISPLAY 1.234043 (-1650 1850);
PAINT GREEN (-1650 1850);
DISPLAY INVISIBLE (-1650 1850);
FORCEPROP 1 LAST HDL_TAP TRUE
J 2
(-1975 1775);
DISPLAY 1.234043 (-1975 1775);
PAINT GREEN (-1975 1775);
DISPLAY INVISIBLE (-1975 1775);
FORCEPROP 1 LAST PATH I105
J 2
(-1650 1900);
DISPLAY 0.936170 (-1650 1900);
PAINT GREEN (-1650 1900);
DISPLAY INVISIBLE (-1650 1900);
FORCEADD TAP..6
R 2
(-1650 2000);
FORCEPROP 3 LASTPIN (-1700 2000) SIG_NAME M_F_DQ<8>
J 0
(-1690 2010);
DISPLAY 0.659574 (-1690 2010);
PAINT MONO (-1690 2010);
DISPLAY INVISIBLE (-1690 2010);
FORCEPROP 1 LASTPIN (-1700 2000) BN 8
J 2
(-1650 2010);
DISPLAY 0.617021 (-1650 2010);
PAINT PINK (-1650 2010);
FORCEPROP 2 LAST CDS_LIB mstr_standard
J 2
(-1650 2000);
DISPLAY 0.787234 (-1650 2000);
PAINT MONO (-1650 2000);
DISPLAY INVISIBLE (-1650 2000);
FORCEPROP 1 LAST BODY_TYPE PLUMBING
J 2
(-1650 1950);
DISPLAY 1.234043 (-1650 1950);
PAINT GREEN (-1650 1950);
DISPLAY INVISIBLE (-1650 1950);
FORCEPROP 1 LAST HDL_TAP TRUE
J 2
(-1975 1875);
DISPLAY 1.234043 (-1975 1875);
PAINT GREEN (-1975 1875);
DISPLAY INVISIBLE (-1975 1875);
FORCEPROP 1 LAST PATH I106
J 2
(-1650 2000);
DISPLAY 0.936170 (-1650 2000);
PAINT GREEN (-1650 2000);
DISPLAY INVISIBLE (-1650 2000);
FORCEADD TAP..6
R 2
(-1650 1950);
FORCEPROP 3 LASTPIN (-1700 1950) SIG_NAME M_F_DQ<7>
J 0
(-1690 1960);
DISPLAY 0.659574 (-1690 1960);
PAINT MONO (-1690 1960);
DISPLAY INVISIBLE (-1690 1960);
FORCEPROP 1 LASTPIN (-1700 1950) BN 7
J 2
(-1650 1960);
DISPLAY 0.617021 (-1650 1960);
PAINT PINK (-1650 1960);
FORCEPROP 2 LAST CDS_LIB mstr_standard
J 2
(-1650 1950);
DISPLAY 0.787234 (-1650 1950);
PAINT MONO (-1650 1950);
DISPLAY INVISIBLE (-1650 1950);
FORCEPROP 1 LAST BODY_TYPE PLUMBING
J 2
(-1650 1900);
DISPLAY 1.234043 (-1650 1900);
PAINT GREEN (-1650 1900);
DISPLAY INVISIBLE (-1650 1900);
FORCEPROP 1 LAST HDL_TAP TRUE
J 2
(-1975 1825);
DISPLAY 1.234043 (-1975 1825);
PAINT GREEN (-1975 1825);
DISPLAY INVISIBLE (-1975 1825);
FORCEPROP 1 LAST PATH I107
J 2
(-1650 1950);
DISPLAY 0.936170 (-1650 1950);
PAINT GREEN (-1650 1950);
DISPLAY INVISIBLE (-1650 1950);
FORCEADD TAP..6
R 2
(-1650 1600);
FORCEPROP 3 LASTPIN (-1700 1600) SIG_NAME M_F_DQ<0>
J 0
(-1690 1610);
DISPLAY 0.659574 (-1690 1610);
PAINT MONO (-1690 1610);
DISPLAY INVISIBLE (-1690 1610);
FORCEPROP 1 LASTPIN (-1700 1600) BN 0
J 2
(-1650 1610);
DISPLAY 0.617021 (-1650 1610);
PAINT PINK (-1650 1610);
FORCEPROP 2 LAST CDS_LIB mstr_standard
J 2
(-1650 1600);
DISPLAY 0.787234 (-1650 1600);
PAINT MONO (-1650 1600);
DISPLAY INVISIBLE (-1650 1600);
FORCEPROP 1 LAST BODY_TYPE PLUMBING
J 2
(-1650 1550);
DISPLAY 1.234043 (-1650 1550);
PAINT GREEN (-1650 1550);
DISPLAY INVISIBLE (-1650 1550);
FORCEPROP 1 LAST HDL_TAP TRUE
J 2
(-1975 1475);
DISPLAY 1.234043 (-1975 1475);
PAINT GREEN (-1975 1475);
DISPLAY INVISIBLE (-1975 1475);
FORCEPROP 1 LAST PATH I108
J 2
(-1650 1600);
DISPLAY 0.936170 (-1650 1600);
PAINT GREEN (-1650 1600);
DISPLAY INVISIBLE (-1650 1600);
FORCEADD TAP..6
R 2
(-1650 1700);
FORCEPROP 3 LASTPIN (-1700 1700) SIG_NAME M_F_DQ<2>
J 0
(-1690 1710);
DISPLAY 0.659574 (-1690 1710);
PAINT MONO (-1690 1710);
DISPLAY INVISIBLE (-1690 1710);
FORCEPROP 1 LASTPIN (-1700 1700) BN 2
J 2
(-1650 1710);
DISPLAY 0.617021 (-1650 1710);
PAINT PINK (-1650 1710);
FORCEPROP 2 LAST CDS_LIB mstr_standard
J 2
(-1650 1700);
DISPLAY 0.787234 (-1650 1700);
PAINT MONO (-1650 1700);
DISPLAY INVISIBLE (-1650 1700);
FORCEPROP 1 LAST BODY_TYPE PLUMBING
J 2
(-1650 1650);
DISPLAY 1.234043 (-1650 1650);
PAINT GREEN (-1650 1650);
DISPLAY INVISIBLE (-1650 1650);
FORCEPROP 1 LAST HDL_TAP TRUE
J 2
(-1975 1575);
DISPLAY 1.234043 (-1975 1575);
PAINT GREEN (-1975 1575);
DISPLAY INVISIBLE (-1975 1575);
FORCEPROP 1 LAST PATH I109
J 2
(-1650 1700);
DISPLAY 0.936170 (-1650 1700);
PAINT GREEN (-1650 1700);
DISPLAY INVISIBLE (-1650 1700);
FORCEADD TAP..6
R 2
(700 4950);
FORCEPROP 3 LASTPIN (650 4950) SIG_NAME M_F_DQS_DP<15>
J 0
(660 4960);
DISPLAY 0.659574 (660 4960);
PAINT MONO (660 4960);
DISPLAY INVISIBLE (660 4960);
FORCEPROP 1 LASTPIN (650 4950) BN 15
J 2
(700 4960);
DISPLAY 0.617021 (700 4960);
PAINT PINK (700 4960);
FORCEPROP 2 LAST CDS_LIB mstr_standard
J 0
(700 4950);
DISPLAY 0.787234 (700 4950);
PAINT MONO (700 4950);
DISPLAY INVISIBLE (700 4950);
FORCEPROP 1 LAST BODY_TYPE PLUMBING
J 2
(700 4900);
DISPLAY 1.234043 (700 4900);
PAINT GREEN (700 4900);
DISPLAY INVISIBLE (700 4900);
FORCEPROP 1 LAST HDL_TAP TRUE
J 2
(375 4825);
DISPLAY 1.234043 (375 4825);
PAINT GREEN (375 4825);
DISPLAY INVISIBLE (375 4825);
FORCEPROP 1 LAST PATH I11
J 2
(700 4950);
DISPLAY 0.936170 (700 4950);
PAINT GREEN (700 4950);
DISPLAY INVISIBLE (700 4950);
FORCEADD TAP..6
R 2
(-1650 1650);
FORCEPROP 3 LASTPIN (-1700 1650) SIG_NAME M_F_DQ<1>
J 0
(-1690 1660);
DISPLAY 0.659574 (-1690 1660);
PAINT MONO (-1690 1660);
DISPLAY INVISIBLE (-1690 1660);
FORCEPROP 1 LASTPIN (-1700 1650) BN 1
J 2
(-1650 1660);
DISPLAY 0.617021 (-1650 1660);
PAINT PINK (-1650 1660);
FORCEPROP 2 LAST CDS_LIB mstr_standard
J 2
(-1650 1650);
DISPLAY 0.787234 (-1650 1650);
PAINT MONO (-1650 1650);
DISPLAY INVISIBLE (-1650 1650);
FORCEPROP 1 LAST BODY_TYPE PLUMBING
J 2
(-1650 1600);
DISPLAY 1.234043 (-1650 1600);
PAINT GREEN (-1650 1600);
DISPLAY INVISIBLE (-1650 1600);
FORCEPROP 1 LAST HDL_TAP TRUE
J 2
(-1975 1525);
DISPLAY 1.234043 (-1975 1525);
PAINT GREEN (-1975 1525);
DISPLAY INVISIBLE (-1975 1525);
FORCEPROP 1 LAST PATH I110
J 2
(-1650 1650);
DISPLAY 0.936170 (-1650 1650);
PAINT GREEN (-1650 1650);
DISPLAY INVISIBLE (-1650 1650);
FORCEADD SCONN288_H44441003..1
(-2400 3100);
FORCEPROP 1 LAST LOCATION J6L1
J 0
(-2850 5000);
DISPLAY 0.617021 (-2850 5000);
PAINT AQUA (-2850 5000);
FORCEPROP 1 LAST PART_NUMBER H44441-003
J 0
(-2850 1100);
DISPLAY 0.617021 (-2850 1100);
PAINT BLUE (-2850 1100);
FORCEPROP 1 LAST MATERIAL SCONN
J 0
(-2850 4950);
DISPLAY 0.617021 (-2850 4950);
PAINT SKYBLUE (-2850 4950);
FORCEPROP 2 LASTPIN (-2900 1600) $PN 146
J 2
(-2910 1610);
DISPLAY 0.617021 (-2910 1610);
PAINT ORANGE (-2910 1610);
FORCEPROP 2 LASTPIN (-2900 1950) $PN 284
J 2
(-2910 1960);
DISPLAY 0.617021 (-2910 1960);
PAINT ORANGE (-2910 1960);
FORCEPROP 2 LASTPIN (-2900 1750) $PN 285
J 2
(-2910 1760);
DISPLAY 0.617021 (-2910 1760);
PAINT ORANGE (-2910 1760);
FORCEPROP 2 LASTPIN (-2900 1700) $PN 141
J 2
(-2910 1710);
DISPLAY 0.617021 (-2910 1710);
PAINT ORANGE (-2910 1710);
FORCEPROP 2 LASTPIN (-2900 1300) $PN 230
J 2
(-2910 1310);
DISPLAY 0.617021 (-2910 1310);
PAINT ORANGE (-2910 1310);
FORCEPROP 2 LASTPIN (-2900 1900) $PN 238
J 2
(-2910 1910);
DISPLAY 0.617021 (-2910 1910);
PAINT ORANGE (-2910 1910);
FORCEPROP 2 LASTPIN (-2900 1850) $PN 140
J 2
(-2910 1860);
DISPLAY 0.617021 (-2910 1860);
PAINT ORANGE (-2910 1860);
FORCEPROP 2 LASTPIN (-2900 1800) $PN 139
J 2
(-2910 1810);
DISPLAY 0.617021 (-2910 1810);
PAINT ORANGE (-2910 1810);
FORCEPROP 2 LASTPIN (-2900 3250) $PN 237
J 2
(-2910 3260);
DISPLAY 0.617021 (-2910 3260);
PAINT ORANGE (-2910 3260);
FORCEPROP 2 LASTPIN (-2900 3200) $PN 93
J 2
(-2910 3210);
DISPLAY 0.617021 (-2910 3210);
PAINT ORANGE (-2910 3210);
FORCEPROP 2 LASTPIN (-2900 3150) $PN 89
J 2
(-2910 3160);
DISPLAY 0.617021 (-2910 3160);
PAINT ORANGE (-2910 3160);
FORCEPROP 2 LASTPIN (-2900 3100) $PN 84
J 2
(-2910 3110);
DISPLAY 0.617021 (-2910 3110);
PAINT ORANGE (-2910 3110);
FORCEPROP 2 LASTPIN (-2900 1500) $PN 144
J 2
(-2910 1510);
DISPLAY 0.617021 (-2910 1510);
PAINT ORANGE (-2910 1510);
FORCEPROP 2 LASTPIN (-2900 1450) $PN 227
J 2
(-2910 1460);
DISPLAY 0.617021 (-2910 1460);
PAINT ORANGE (-2910 1460);
FORCEPROP 2 LASTPIN (-2900 1400) $PN 205
J 2
(-2910 1410);
DISPLAY 0.617021 (-2910 1410);
PAINT ORANGE (-2910 1410);
FORCEPROP 2 LASTPIN (-2900 2200) $PN 58
J 2
(-2910 2210);
DISPLAY 0.617021 (-2910 2210);
PAINT ORANGE (-2910 2210);
FORCEPROP 2 LASTPIN (-2900 2250) $PN 222
J 2
(-2910 2260);
DISPLAY 0.617021 (-2910 2260);
PAINT ORANGE (-2910 2260);
FORCEPROP 2 LASTPIN (-2900 2850) $PN 91
J 2
(-2910 2860);
DISPLAY 0.617021 (-2910 2860);
PAINT ORANGE (-2910 2860);
FORCEPROP 2 LASTPIN (-2900 2800) $PN 87
J 2
(-2910 2810);
DISPLAY 0.617021 (-2910 2810);
PAINT ORANGE (-2910 2810);
FORCEPROP 2 LASTPIN (-2900 2150) $PN 78
J 2
(-2910 2160);
DISPLAY 0.617021 (-2910 2160);
PAINT ORANGE (-2910 2160);
FORCEPROP 2 LASTPIN (-1900 4750) $PN 280
J 0
(-1890 4760);
DISPLAY 0.617021 (-1890 4760);
PAINT ORANGE (-1890 4760);
FORCEPROP 2 LASTPIN (-1900 4700) $PN 135
J 0
(-1890 4710);
DISPLAY 0.617021 (-1890 4710);
PAINT ORANGE (-1890 4710);
FORCEPROP 2 LASTPIN (-1900 4650) $PN 273
J 0
(-1890 4660);
DISPLAY 0.617021 (-1890 4660);
PAINT ORANGE (-1890 4660);
FORCEPROP 2 LASTPIN (-1900 4600) $PN 128
J 0
(-1890 4610);
DISPLAY 0.617021 (-1890 4610);
PAINT ORANGE (-1890 4610);
FORCEPROP 2 LASTPIN (-1900 4550) $PN 282
J 0
(-1890 4560);
DISPLAY 0.617021 (-1890 4560);
PAINT ORANGE (-1890 4560);
FORCEPROP 2 LASTPIN (-1900 4500) $PN 137
J 0
(-1890 4510);
DISPLAY 0.617021 (-1890 4510);
PAINT ORANGE (-1890 4510);
FORCEPROP 2 LASTPIN (-1900 4450) $PN 275
J 0
(-1890 4460);
DISPLAY 0.617021 (-1890 4460);
PAINT ORANGE (-1890 4460);
FORCEPROP 2 LASTPIN (-1900 4400) $PN 130
J 0
(-1890 4410);
DISPLAY 0.617021 (-1890 4410);
PAINT ORANGE (-1890 4410);
FORCEPROP 2 LASTPIN (-1900 4350) $PN 269
J 0
(-1890 4360);
DISPLAY 0.617021 (-1890 4360);
PAINT ORANGE (-1890 4360);
FORCEPROP 2 LASTPIN (-1900 4300) $PN 124
J 0
(-1890 4310);
DISPLAY 0.617021 (-1890 4310);
PAINT ORANGE (-1890 4310);
FORCEPROP 2 LASTPIN (-1900 4250) $PN 262
J 0
(-1890 4260);
DISPLAY 0.617021 (-1890 4260);
PAINT ORANGE (-1890 4260);
FORCEPROP 2 LASTPIN (-1900 4200) $PN 117
J 0
(-1890 4210);
DISPLAY 0.617021 (-1890 4210);
PAINT ORANGE (-1890 4210);
FORCEPROP 2 LASTPIN (-1900 4150) $PN 271
J 0
(-1890 4160);
DISPLAY 0.617021 (-1890 4160);
PAINT ORANGE (-1890 4160);
FORCEPROP 2 LASTPIN (-1900 4100) $PN 126
J 0
(-1890 4110);
DISPLAY 0.617021 (-1890 4110);
PAINT ORANGE (-1890 4110);
FORCEPROP 2 LASTPIN (-1900 4050) $PN 264
J 0
(-1890 4060);
DISPLAY 0.617021 (-1890 4060);
PAINT ORANGE (-1890 4060);
FORCEPROP 2 LASTPIN (-1900 4000) $PN 119
J 0
(-1890 4010);
DISPLAY 0.617021 (-1890 4010);
PAINT ORANGE (-1890 4010);
FORCEPROP 2 LASTPIN (-1900 3950) $PN 258
J 0
(-1890 3960);
DISPLAY 0.617021 (-1890 3960);
PAINT ORANGE (-1890 3960);
FORCEPROP 2 LASTPIN (-1900 3900) $PN 113
J 0
(-1890 3910);
DISPLAY 0.617021 (-1890 3910);
PAINT ORANGE (-1890 3910);
FORCEPROP 2 LASTPIN (-1900 3850) $PN 251
J 0
(-1890 3860);
DISPLAY 0.617021 (-1890 3860);
PAINT ORANGE (-1890 3860);
FORCEPROP 2 LASTPIN (-1900 3800) $PN 106
J 0
(-1890 3810);
DISPLAY 0.617021 (-1890 3810);
PAINT ORANGE (-1890 3810);
FORCEPROP 2 LASTPIN (-1900 3750) $PN 260
J 0
(-1890 3760);
DISPLAY 0.617021 (-1890 3760);
PAINT ORANGE (-1890 3760);
FORCEPROP 2 LASTPIN (-1900 3700) $PN 115
J 0
(-1890 3710);
DISPLAY 0.617021 (-1890 3710);
PAINT ORANGE (-1890 3710);
FORCEPROP 2 LASTPIN (-1900 3650) $PN 253
J 0
(-1890 3660);
DISPLAY 0.617021 (-1890 3660);
PAINT ORANGE (-1890 3660);
FORCEPROP 2 LASTPIN (-1900 3600) $PN 108
J 0
(-1890 3610);
DISPLAY 0.617021 (-1890 3610);
PAINT ORANGE (-1890 3610);
FORCEPROP 2 LASTPIN (-1900 3550) $PN 247
J 0
(-1890 3560);
DISPLAY 0.617021 (-1890 3560);
PAINT ORANGE (-1890 3560);
FORCEPROP 2 LASTPIN (-1900 3500) $PN 102
J 0
(-1890 3510);
DISPLAY 0.617021 (-1890 3510);
PAINT ORANGE (-1890 3510);
FORCEPROP 2 LASTPIN (-1900 3450) $PN 240
J 0
(-1890 3460);
DISPLAY 0.617021 (-1890 3460);
PAINT ORANGE (-1890 3460);
FORCEPROP 2 LASTPIN (-1900 3400) $PN 95
J 0
(-1890 3410);
DISPLAY 0.617021 (-1890 3410);
PAINT ORANGE (-1890 3410);
FORCEPROP 2 LASTPIN (-1900 3350) $PN 249
J 0
(-1890 3360);
DISPLAY 0.617021 (-1890 3360);
PAINT ORANGE (-1890 3360);
FORCEPROP 2 LASTPIN (-1900 3300) $PN 104
J 0
(-1890 3310);
DISPLAY 0.617021 (-1890 3310);
PAINT ORANGE (-1890 3310);
FORCEPROP 2 LASTPIN (-1900 3250) $PN 242
J 0
(-1890 3260);
DISPLAY 0.617021 (-1890 3260);
PAINT ORANGE (-1890 3260);
FORCEPROP 2 LASTPIN (-1900 3200) $PN 97
J 0
(-1890 3210);
DISPLAY 0.617021 (-1890 3210);
PAINT ORANGE (-1890 3210);
FORCEPROP 2 LASTPIN (-1900 3150) $PN 188
J 0
(-1890 3160);
DISPLAY 0.617021 (-1890 3160);
PAINT ORANGE (-1890 3160);
FORCEPROP 2 LASTPIN (-1900 3100) $PN 43
J 0
(-1890 3110);
DISPLAY 0.617021 (-1890 3110);
PAINT ORANGE (-1890 3110);
FORCEPROP 2 LASTPIN (-1900 3050) $PN 181
J 0
(-1890 3060);
DISPLAY 0.617021 (-1890 3060);
PAINT ORANGE (-1890 3060);
FORCEPROP 2 LASTPIN (-1900 3000) $PN 36
J 0
(-1890 3010);
DISPLAY 0.617021 (-1890 3010);
PAINT ORANGE (-1890 3010);
FORCEPROP 2 LASTPIN (-1900 2950) $PN 190
J 0
(-1890 2960);
DISPLAY 0.617021 (-1890 2960);
PAINT ORANGE (-1890 2960);
FORCEPROP 2 LASTPIN (-1900 2900) $PN 45
J 0
(-1890 2910);
DISPLAY 0.617021 (-1890 2910);
PAINT ORANGE (-1890 2910);
FORCEPROP 2 LASTPIN (-1900 2850) $PN 183
J 0
(-1890 2860);
DISPLAY 0.617021 (-1890 2860);
PAINT ORANGE (-1890 2860);
FORCEPROP 2 LASTPIN (-1900 2800) $PN 38
J 0
(-1890 2810);
DISPLAY 0.617021 (-1890 2810);
PAINT ORANGE (-1890 2810);
FORCEPROP 2 LASTPIN (-1900 2750) $PN 177
J 0
(-1890 2760);
DISPLAY 0.617021 (-1890 2760);
PAINT ORANGE (-1890 2760);
FORCEPROP 2 LASTPIN (-1900 2700) $PN 32
J 0
(-1890 2710);
DISPLAY 0.617021 (-1890 2710);
PAINT ORANGE (-1890 2710);
FORCEPROP 2 LASTPIN (-1900 2650) $PN 170
J 0
(-1890 2660);
DISPLAY 0.617021 (-1890 2660);
PAINT ORANGE (-1890 2660);
FORCEPROP 2 LASTPIN (-1900 2600) $PN 25
J 0
(-1890 2610);
DISPLAY 0.617021 (-1890 2610);
PAINT ORANGE (-1890 2610);
FORCEPROP 2 LASTPIN (-1900 2550) $PN 179
J 0
(-1890 2560);
DISPLAY 0.617021 (-1890 2560);
PAINT ORANGE (-1890 2560);
FORCEPROP 2 LASTPIN (-1900 2500) $PN 34
J 0
(-1890 2510);
DISPLAY 0.617021 (-1890 2510);
PAINT ORANGE (-1890 2510);
FORCEPROP 2 LASTPIN (-1900 2450) $PN 172
J 0
(-1890 2460);
DISPLAY 0.617021 (-1890 2460);
PAINT ORANGE (-1890 2460);
FORCEPROP 2 LASTPIN (-1900 2400) $PN 27
J 0
(-1890 2410);
DISPLAY 0.617021 (-1890 2410);
PAINT ORANGE (-1890 2410);
FORCEPROP 2 LASTPIN (-1900 2350) $PN 166
J 0
(-1890 2360);
DISPLAY 0.617021 (-1890 2360);
PAINT ORANGE (-1890 2360);
FORCEPROP 2 LASTPIN (-1900 2300) $PN 21
J 0
(-1890 2310);
DISPLAY 0.617021 (-1890 2310);
PAINT ORANGE (-1890 2310);
FORCEPROP 2 LASTPIN (-1900 2250) $PN 159
J 0
(-1890 2260);
DISPLAY 0.617021 (-1890 2260);
PAINT ORANGE (-1890 2260);
FORCEPROP 2 LASTPIN (-1900 2200) $PN 14
J 0
(-1890 2210);
DISPLAY 0.617021 (-1890 2210);
PAINT ORANGE (-1890 2210);
FORCEPROP 2 LASTPIN (-1900 2150) $PN 168
J 0
(-1890 2160);
DISPLAY 0.617021 (-1890 2160);
PAINT ORANGE (-1890 2160);
FORCEPROP 2 LASTPIN (-1900 2100) $PN 23
J 0
(-1890 2110);
DISPLAY 0.617021 (-1890 2110);
PAINT ORANGE (-1890 2110);
FORCEPROP 2 LASTPIN (-1900 2050) $PN 161
J 0
(-1890 2060);
DISPLAY 0.617021 (-1890 2060);
PAINT ORANGE (-1890 2060);
FORCEPROP 2 LASTPIN (-1900 2000) $PN 16
J 0
(-1890 2010);
DISPLAY 0.617021 (-1890 2010);
PAINT ORANGE (-1890 2010);
FORCEPROP 2 LASTPIN (-1900 1950) $PN 155
J 0
(-1890 1960);
DISPLAY 0.617021 (-1890 1960);
PAINT ORANGE (-1890 1960);
FORCEPROP 2 LASTPIN (-1900 1900) $PN 10
J 0
(-1890 1910);
DISPLAY 0.617021 (-1890 1910);
PAINT ORANGE (-1890 1910);
FORCEPROP 2 LASTPIN (-1900 1850) $PN 148
J 0
(-1890 1860);
DISPLAY 0.617021 (-1890 1860);
PAINT ORANGE (-1890 1860);
FORCEPROP 2 LASTPIN (-1900 1800) $PN 3
J 0
(-1890 1810);
DISPLAY 0.617021 (-1890 1810);
PAINT ORANGE (-1890 1810);
FORCEPROP 2 LASTPIN (-1900 1750) $PN 157
J 0
(-1890 1760);
DISPLAY 0.617021 (-1890 1760);
PAINT ORANGE (-1890 1760);
FORCEPROP 2 LASTPIN (-1900 1700) $PN 12
J 0
(-1890 1710);
DISPLAY 0.617021 (-1890 1710);
PAINT ORANGE (-1890 1710);
FORCEPROP 2 LASTPIN (-1900 1650) $PN 150
J 0
(-1890 1660);
DISPLAY 0.617021 (-1890 1660);
PAINT ORANGE (-1890 1660);
FORCEPROP 2 LASTPIN (-1900 1600) $PN 5
J 0
(-1890 1610);
DISPLAY 0.617021 (-1890 1610);
PAINT ORANGE (-1890 1610);
FORCEPROP 2 LASTPIN (-2900 3000) $PN 203
J 2
(-2910 3010);
DISPLAY 0.617021 (-2910 3010);
PAINT ORANGE (-2910 3010);
FORCEPROP 2 LASTPIN (-2900 2950) $PN 60
J 2
(-2910 2960);
DISPLAY 0.617021 (-2910 2960);
PAINT ORANGE (-2910 2960);
FORCEPROP 2 LASTPIN (-2900 3550) $PN 218
J 2
(-2910 3560);
DISPLAY 0.617021 (-2910 3560);
PAINT ORANGE (-2910 3560);
FORCEPROP 2 LASTPIN (-2900 3500) $PN 219
J 2
(-2910 3510);
DISPLAY 0.617021 (-2910 3510);
PAINT ORANGE (-2910 3510);
FORCEPROP 2 LASTPIN (-2900 3450) $PN 74
J 2
(-2910 3460);
DISPLAY 0.617021 (-2910 3460);
PAINT ORANGE (-2910 3460);
FORCEPROP 2 LASTPIN (-2900 3400) $PN 75
J 2
(-2910 3410);
DISPLAY 0.617021 (-2910 3410);
PAINT ORANGE (-2910 3410);
FORCEPROP 2 LASTPIN (-2900 2700) $PN 199
J 2
(-2910 2710);
DISPLAY 0.617021 (-2910 2710);
PAINT ORANGE (-2910 2710);
FORCEPROP 2 LASTPIN (-2900 2650) $PN 54
J 2
(-2910 2660);
DISPLAY 0.617021 (-2910 2660);
PAINT ORANGE (-2910 2660);
FORCEPROP 2 LASTPIN (-2900 2600) $PN 192
J 2
(-2910 2610);
DISPLAY 0.617021 (-2910 2610);
PAINT ORANGE (-2910 2610);
FORCEPROP 2 LASTPIN (-2900 2550) $PN 47
J 2
(-2910 2560);
DISPLAY 0.617021 (-2910 2560);
PAINT ORANGE (-2910 2560);
FORCEPROP 2 LASTPIN (-2900 2500) $PN 201
J 2
(-2910 2510);
DISPLAY 0.617021 (-2910 2510);
PAINT ORANGE (-2910 2510);
FORCEPROP 2 LASTPIN (-2900 2450) $PN 56
J 2
(-2910 2460);
DISPLAY 0.617021 (-2910 2460);
PAINT ORANGE (-2910 2460);
FORCEPROP 2 LASTPIN (-2900 2400) $PN 194
J 2
(-2910 2410);
DISPLAY 0.617021 (-2910 2410);
PAINT ORANGE (-2910 2410);
FORCEPROP 2 LASTPIN (-2900 2350) $PN 49
J 2
(-2910 2360);
DISPLAY 0.617021 (-2910 2360);
PAINT ORANGE (-2910 2360);
FORCEPROP 2 LASTPIN (-2900 3300) $PN 235
J 2
(-2910 3310);
DISPLAY 0.617021 (-2910 3310);
PAINT ORANGE (-2910 3310);
FORCEPROP 2 LASTPIN (-2900 3700) $PN 207
J 2
(-2910 3710);
DISPLAY 0.617021 (-2910 3710);
PAINT ORANGE (-2910 3710);
FORCEPROP 2 LASTPIN (-2900 3650) $PN 63
J 2
(-2910 3660);
DISPLAY 0.617021 (-2910 3660);
PAINT ORANGE (-2910 3660);
FORCEPROP 2 LASTPIN (-2900 3800) $PN 224
J 2
(-2910 3810);
DISPLAY 0.617021 (-2910 3810);
PAINT ORANGE (-2910 3810);
FORCEPROP 2 LASTPIN (-2900 3750) $PN 81
J 2
(-2910 3760);
DISPLAY 0.617021 (-2910 3760);
PAINT ORANGE (-2910 3760);
FORCEPROP 2 LASTPIN (-2900 2100) $PN 208
J 2
(-2910 2110);
DISPLAY 0.617021 (-2910 2110);
PAINT ORANGE (-2910 2110);
FORCEPROP 2 LASTPIN (-2900 2050) $PN 62
J 2
(-2910 2060);
DISPLAY 0.617021 (-2910 2060);
PAINT ORANGE (-2910 2060);
FORCEPROP 2 LASTPIN (-2900 4750) $PN 234
J 2
(-2910 4760);
DISPLAY 0.617021 (-2910 4760);
PAINT ORANGE (-2910 4760);
FORCEPROP 2 LASTPIN (-2900 4700) $PN 82
J 2
(-2910 4710);
DISPLAY 0.617021 (-2910 4710);
PAINT ORANGE (-2910 4710);
FORCEPROP 2 LASTPIN (-2900 4650) $PN 86
J 2
(-2910 4660);
DISPLAY 0.617021 (-2910 4660);
PAINT ORANGE (-2910 4660);
FORCEPROP 2 LASTPIN (-2900 4600) $PN 228
J 2
(-2910 4610);
DISPLAY 0.617021 (-2910 4610);
PAINT ORANGE (-2910 4610);
FORCEPROP 2 LASTPIN (-2900 4550) $PN 232
J 2
(-2910 4560);
DISPLAY 0.617021 (-2910 4560);
PAINT ORANGE (-2910 4560);
FORCEPROP 2 LASTPIN (-2900 4500) $PN 65
J 2
(-2910 4510);
DISPLAY 0.617021 (-2910 4510);
PAINT ORANGE (-2910 4510);
FORCEPROP 2 LASTPIN (-2900 4450) $PN 210
J 2
(-2910 4460);
DISPLAY 0.617021 (-2910 4460);
PAINT ORANGE (-2910 4460);
FORCEPROP 2 LASTPIN (-2900 4400) $PN 225
J 2
(-2910 4410);
DISPLAY 0.617021 (-2910 4410);
PAINT ORANGE (-2910 4410);
FORCEPROP 2 LASTPIN (-2900 4350) $PN 66
J 2
(-2910 4360);
DISPLAY 0.617021 (-2910 4360);
PAINT ORANGE (-2910 4360);
FORCEPROP 2 LASTPIN (-2900 4300) $PN 68
J 2
(-2910 4310);
DISPLAY 0.617021 (-2910 4310);
PAINT ORANGE (-2910 4310);
FORCEPROP 2 LASTPIN (-2900 4250) $PN 211
J 2
(-2910 4260);
DISPLAY 0.617021 (-2910 4260);
PAINT ORANGE (-2910 4260);
FORCEPROP 2 LASTPIN (-2900 4200) $PN 69
J 2
(-2910 4210);
DISPLAY 0.617021 (-2910 4210);
PAINT ORANGE (-2910 4210);
FORCEPROP 2 LASTPIN (-2900 4150) $PN 213
J 2
(-2910 4160);
DISPLAY 0.617021 (-2910 4160);
PAINT ORANGE (-2910 4160);
FORCEPROP 2 LASTPIN (-2900 4100) $PN 214
J 2
(-2910 4110);
DISPLAY 0.617021 (-2910 4110);
PAINT ORANGE (-2910 4110);
FORCEPROP 2 LASTPIN (-2900 4050) $PN 71
J 2
(-2910 4060);
DISPLAY 0.617021 (-2910 4060);
PAINT ORANGE (-2910 4060);
FORCEPROP 2 LASTPIN (-2900 4000) $PN 216
J 2
(-2910 4010);
DISPLAY 0.617021 (-2910 4010);
PAINT ORANGE (-2910 4010);
FORCEPROP 2 LASTPIN (-2900 3950) $PN 72
J 2
(-2910 3960);
DISPLAY 0.617021 (-2910 3960);
PAINT ORANGE (-2910 3960);
FORCEPROP 2 LASTPIN (-2900 3900) $PN 79
J 2
(-2910 3910);
DISPLAY 0.617021 (-2910 3910);
PAINT ORANGE (-2910 3910);
FORCEPROP 1 LAST PACK_TYPE PIP
J 0
(-2850 5050);
PAINT SKYBLUE (-2850 5050);
DISPLAY INVISIBLE (-2850 5050);
FORCEPROP 2 LAST BOM_COST MEM
J 0
(-2400 3100);
PAINT ORANGE (-2400 3100);
DISPLAY INVISIBLE (-2400 3100);
FORCEPROP 2 LAST CDS_LIB mstr_sconn
J 0
(-2400 3100);
PAINT ORANGE (-2400 3100);
DISPLAY INVISIBLE (-2400 3100);
FORCEPROP 2 LAST SEC_TYPE PIP
J 0
(-2850 5050);
DISPLAY 1.021277 (-2850 5050);
PAINT ORANGE (-2850 5050);
DISPLAY INVISIBLE (-2850 5050);
FORCEPROP 2 LAST SEC 1
J 0
(-2850 5050);
DISPLAY 0.680851 (-2850 5050);
PAINT MONO (-2850 5050);
DISPLAY INVISIBLE (-2850 5050);
FORCEPROP 2 LAST CDS_LOCATION J6L1
J 0
(-2850 5000);
DISPLAY 0.617021 (-2850 5000);
PAINT AQUA (-2850 5000);
DISPLAY INVISIBLE (-2850 5000);
FORCEPROP 1 LAST PATH I111
J 0
(-2400 4950);
PAINT GREEN (-2400 4950);
DISPLAY INVISIBLE (-2400 4950);
FORCEPROP 2 LAST ROOM DDR4_CH_F1
J 0
(-2400 3100);
PAINT ORANGE (-2400 3100);
DISPLAY INVISIBLE (-2400 3100);
FORCEADD TAP..6
(-3150 4700);
FORCEPROP 3 LASTPIN (-3100 4700) SIG_NAME M_F_MA<16>
J 0
(-3090 4710);
DISPLAY 0.659574 (-3090 4710);
PAINT MONO (-3090 4710);
DISPLAY INVISIBLE (-3090 4710);
FORCEPROP 1 LASTPIN (-3100 4700) BN 16
J 0
(-3150 4710);
DISPLAY 0.617021 (-3150 4710);
PAINT PINK (-3150 4710);
FORCEPROP 2 LAST CDS_LIB mstr_standard
J 2
(-3150 4700);
DISPLAY 0.787234 (-3150 4700);
PAINT MONO (-3150 4700);
DISPLAY INVISIBLE (-3150 4700);
FORCEPROP 1 LAST BODY_TYPE PLUMBING
J 0
(-3150 4650);
DISPLAY 1.234043 (-3150 4650);
PAINT GREEN (-3150 4650);
DISPLAY INVISIBLE (-3150 4650);
FORCEPROP 1 LAST HDL_TAP TRUE
J 0
(-2825 4575);
DISPLAY 1.234043 (-2825 4575);
PAINT GREEN (-2825 4575);
DISPLAY INVISIBLE (-2825 4575);
FORCEPROP 1 LAST PATH I112
J 0
(-3150 4700);
DISPLAY 0.936170 (-3150 4700);
PAINT GREEN (-3150 4700);
DISPLAY INVISIBLE (-3150 4700);
FORCEADD TAP..6
(-3150 4750);
FORCEPROP 3 LASTPIN (-3100 4750) SIG_NAME M_F_MA<17>
J 0
(-3090 4760);
DISPLAY 0.659574 (-3090 4760);
PAINT MONO (-3090 4760);
DISPLAY INVISIBLE (-3090 4760);
FORCEPROP 1 LASTPIN (-3100 4750) BN 17
J 0
(-3150 4760);
DISPLAY 0.617021 (-3150 4760);
PAINT PINK (-3150 4760);
FORCEPROP 2 LAST CDS_LIB mstr_standard
J 0
(-3150 4750);
DISPLAY 0.787234 (-3150 4750);
PAINT MONO (-3150 4750);
DISPLAY INVISIBLE (-3150 4750);
FORCEPROP 1 LAST BODY_TYPE PLUMBING
J 0
(-3150 4700);
DISPLAY 1.234043 (-3150 4700);
PAINT GREEN (-3150 4700);
DISPLAY INVISIBLE (-3150 4700);
FORCEPROP 1 LAST HDL_TAP TRUE
J 0
(-2825 4625);
DISPLAY 1.234043 (-2825 4625);
PAINT GREEN (-2825 4625);
DISPLAY INVISIBLE (-2825 4625);
FORCEPROP 1 LAST PATH I113
J 0
(-3150 4750);
DISPLAY 0.936170 (-3150 4750);
PAINT GREEN (-3150 4750);
DISPLAY INVISIBLE (-3150 4750);
FORCEADD TAP..6
(-3150 4650);
FORCEPROP 3 LASTPIN (-3100 4650) SIG_NAME M_F_MA<15>
J 0
(-3090 4660);
DISPLAY 0.659574 (-3090 4660);
PAINT MONO (-3090 4660);
DISPLAY INVISIBLE (-3090 4660);
FORCEPROP 1 LASTPIN (-3100 4650) BN 15
J 0
(-3150 4660);
DISPLAY 0.617021 (-3150 4660);
PAINT PINK (-3150 4660);
FORCEPROP 2 LAST CDS_LIB mstr_standard
J 2
(-3150 4650);
DISPLAY 0.787234 (-3150 4650);
PAINT MONO (-3150 4650);
DISPLAY INVISIBLE (-3150 4650);
FORCEPROP 1 LAST BODY_TYPE PLUMBING
J 0
(-3150 4600);
DISPLAY 1.234043 (-3150 4600);
PAINT GREEN (-3150 4600);
DISPLAY INVISIBLE (-3150 4600);
FORCEPROP 1 LAST HDL_TAP TRUE
J 0
(-2825 4525);
DISPLAY 1.234043 (-2825 4525);
PAINT GREEN (-2825 4525);
DISPLAY INVISIBLE (-2825 4525);
FORCEPROP 1 LAST PATH I114
J 0
(-3150 4650);
DISPLAY 0.936170 (-3150 4650);
PAINT GREEN (-3150 4650);
DISPLAY INVISIBLE (-3150 4650);
FORCEADD TAP..6
(-3150 4600);
FORCEPROP 3 LASTPIN (-3100 4600) SIG_NAME M_F_MA<14>
J 0
(-3090 4610);
DISPLAY 0.659574 (-3090 4610);
PAINT MONO (-3090 4610);
DISPLAY INVISIBLE (-3090 4610);
FORCEPROP 1 LASTPIN (-3100 4600) BN 14
J 0
(-3150 4610);
DISPLAY 0.617021 (-3150 4610);
PAINT PINK (-3150 4610);
FORCEPROP 2 LAST CDS_LIB mstr_standard
J 2
(-3150 4600);
DISPLAY 0.787234 (-3150 4600);
PAINT MONO (-3150 4600);
DISPLAY INVISIBLE (-3150 4600);
FORCEPROP 1 LAST BODY_TYPE PLUMBING
J 0
(-3150 4550);
DISPLAY 1.234043 (-3150 4550);
PAINT GREEN (-3150 4550);
DISPLAY INVISIBLE (-3150 4550);
FORCEPROP 1 LAST HDL_TAP TRUE
J 0
(-2825 4475);
DISPLAY 1.234043 (-2825 4475);
PAINT GREEN (-2825 4475);
DISPLAY INVISIBLE (-2825 4475);
FORCEPROP 1 LAST PATH I115
J 0
(-3150 4600);
DISPLAY 0.936170 (-3150 4600);
PAINT GREEN (-3150 4600);
DISPLAY INVISIBLE (-3150 4600);
FORCEADD TAP..6
(-3150 4550);
FORCEPROP 3 LASTPIN (-3100 4550) SIG_NAME M_F_MA<13>
J 0
(-3090 4560);
DISPLAY 0.659574 (-3090 4560);
PAINT MONO (-3090 4560);
DISPLAY INVISIBLE (-3090 4560);
FORCEPROP 1 LASTPIN (-3100 4550) BN 13
J 0
(-3150 4560);
DISPLAY 0.617021 (-3150 4560);
PAINT PINK (-3150 4560);
FORCEPROP 2 LAST CDS_LIB mstr_standard
J 2
(-3150 4550);
DISPLAY 0.787234 (-3150 4550);
PAINT MONO (-3150 4550);
DISPLAY INVISIBLE (-3150 4550);
FORCEPROP 1 LAST BODY_TYPE PLUMBING
J 0
(-3150 4500);
DISPLAY 1.234043 (-3150 4500);
PAINT GREEN (-3150 4500);
DISPLAY INVISIBLE (-3150 4500);
FORCEPROP 1 LAST HDL_TAP TRUE
J 0
(-2825 4425);
DISPLAY 1.234043 (-2825 4425);
PAINT GREEN (-2825 4425);
DISPLAY INVISIBLE (-2825 4425);
FORCEPROP 1 LAST PATH I116
J 0
(-3150 4550);
DISPLAY 0.936170 (-3150 4550);
PAINT GREEN (-3150 4550);
DISPLAY INVISIBLE (-3150 4550);
FORCEADD TAP..6
(-3150 4500);
FORCEPROP 3 LASTPIN (-3100 4500) SIG_NAME M_F_MA<12>
J 0
(-3090 4510);
DISPLAY 0.659574 (-3090 4510);
PAINT MONO (-3090 4510);
DISPLAY INVISIBLE (-3090 4510);
FORCEPROP 1 LASTPIN (-3100 4500) BN 12
J 0
(-3150 4510);
DISPLAY 0.617021 (-3150 4510);
PAINT PINK (-3150 4510);
FORCEPROP 2 LAST CDS_LIB mstr_standard
J 2
(-3150 4500);
DISPLAY 0.787234 (-3150 4500);
PAINT MONO (-3150 4500);
DISPLAY INVISIBLE (-3150 4500);
FORCEPROP 1 LAST BODY_TYPE PLUMBING
J 0
(-3150 4450);
DISPLAY 1.234043 (-3150 4450);
PAINT GREEN (-3150 4450);
DISPLAY INVISIBLE (-3150 4450);
FORCEPROP 1 LAST HDL_TAP TRUE
J 0
(-2825 4375);
DISPLAY 1.234043 (-2825 4375);
PAINT GREEN (-2825 4375);
DISPLAY INVISIBLE (-2825 4375);
FORCEPROP 1 LAST PATH I117
J 0
(-3150 4500);
DISPLAY 0.936170 (-3150 4500);
PAINT GREEN (-3150 4500);
DISPLAY INVISIBLE (-3150 4500);
FORCEADD TAP..6
(-3150 4450);
FORCEPROP 3 LASTPIN (-3100 4450) SIG_NAME M_F_MA<11>
J 0
(-3090 4460);
DISPLAY 0.659574 (-3090 4460);
PAINT MONO (-3090 4460);
DISPLAY INVISIBLE (-3090 4460);
FORCEPROP 1 LASTPIN (-3100 4450) BN 11
J 0
(-3150 4460);
DISPLAY 0.617021 (-3150 4460);
PAINT PINK (-3150 4460);
FORCEPROP 2 LAST CDS_LIB mstr_standard
J 2
(-3150 4450);
DISPLAY 0.787234 (-3150 4450);
PAINT MONO (-3150 4450);
DISPLAY INVISIBLE (-3150 4450);
FORCEPROP 1 LAST BODY_TYPE PLUMBING
J 0
(-3150 4400);
DISPLAY 1.234043 (-3150 4400);
PAINT GREEN (-3150 4400);
DISPLAY INVISIBLE (-3150 4400);
FORCEPROP 1 LAST HDL_TAP TRUE
J 0
(-2825 4325);
DISPLAY 1.234043 (-2825 4325);
PAINT GREEN (-2825 4325);
DISPLAY INVISIBLE (-2825 4325);
FORCEPROP 1 LAST PATH I118
J 0
(-3150 4450);
DISPLAY 0.936170 (-3150 4450);
PAINT GREEN (-3150 4450);
DISPLAY INVISIBLE (-3150 4450);
FORCEADD TAP..6
(-3150 4400);
FORCEPROP 3 LASTPIN (-3100 4400) SIG_NAME M_F_MA<10>
J 0
(-3090 4410);
DISPLAY 0.659574 (-3090 4410);
PAINT MONO (-3090 4410);
DISPLAY INVISIBLE (-3090 4410);
FORCEPROP 1 LASTPIN (-3100 4400) BN 10
J 0
(-3150 4410);
DISPLAY 0.617021 (-3150 4410);
PAINT PINK (-3150 4410);
FORCEPROP 2 LAST CDS_LIB mstr_standard
J 2
(-3150 4400);
DISPLAY 0.787234 (-3150 4400);
PAINT MONO (-3150 4400);
DISPLAY INVISIBLE (-3150 4400);
FORCEPROP 1 LAST BODY_TYPE PLUMBING
J 0
(-3150 4350);
DISPLAY 1.234043 (-3150 4350);
PAINT GREEN (-3150 4350);
DISPLAY INVISIBLE (-3150 4350);
FORCEPROP 1 LAST HDL_TAP TRUE
J 0
(-2825 4275);
DISPLAY 1.234043 (-2825 4275);
PAINT GREEN (-2825 4275);
DISPLAY INVISIBLE (-2825 4275);
FORCEPROP 1 LAST PATH I119
J 0
(-3150 4400);
DISPLAY 0.936170 (-3150 4400);
PAINT GREEN (-3150 4400);
DISPLAY INVISIBLE (-3150 4400);
FORCEADD TAP..6
R 2
(700 5050);
FORCEPROP 3 LASTPIN (650 5050) SIG_NAME M_F_DQS_DP<16>
J 0
(660 5060);
DISPLAY 0.659574 (660 5060);
PAINT MONO (660 5060);
DISPLAY INVISIBLE (660 5060);
FORCEPROP 1 LASTPIN (650 5050) BN 16
J 2
(700 5060);
DISPLAY 0.617021 (700 5060);
PAINT PINK (700 5060);
FORCEPROP 2 LAST CDS_LIB mstr_standard
J 0
(700 5050);
DISPLAY 0.787234 (700 5050);
PAINT MONO (700 5050);
DISPLAY INVISIBLE (700 5050);
FORCEPROP 1 LAST BODY_TYPE PLUMBING
J 2
(700 5000);
DISPLAY 1.234043 (700 5000);
PAINT GREEN (700 5000);
DISPLAY INVISIBLE (700 5000);
FORCEPROP 1 LAST HDL_TAP TRUE
J 2
(375 4925);
DISPLAY 1.234043 (375 4925);
PAINT GREEN (375 4925);
DISPLAY INVISIBLE (375 4925);
FORCEPROP 1 LAST PATH I12
J 2
(700 5050);
DISPLAY 0.936170 (700 5050);
PAINT GREEN (700 5050);
DISPLAY INVISIBLE (700 5050);
FORCEADD TAP..6
(-3150 4350);
FORCEPROP 3 LASTPIN (-3100 4350) SIG_NAME M_F_MA<9>
J 0
(-3090 4360);
DISPLAY 0.659574 (-3090 4360);
PAINT MONO (-3090 4360);
DISPLAY INVISIBLE (-3090 4360);
FORCEPROP 1 LASTPIN (-3100 4350) BN 9
J 0
(-3150 4360);
DISPLAY 0.617021 (-3150 4360);
PAINT PINK (-3150 4360);
FORCEPROP 2 LAST CDS_LIB mstr_standard
J 2
(-3150 4350);
DISPLAY 0.787234 (-3150 4350);
PAINT MONO (-3150 4350);
DISPLAY INVISIBLE (-3150 4350);
FORCEPROP 1 LAST BODY_TYPE PLUMBING
J 0
(-3150 4300);
DISPLAY 1.234043 (-3150 4300);
PAINT GREEN (-3150 4300);
DISPLAY INVISIBLE (-3150 4300);
FORCEPROP 1 LAST HDL_TAP TRUE
J 0
(-2825 4225);
DISPLAY 1.234043 (-2825 4225);
PAINT GREEN (-2825 4225);
DISPLAY INVISIBLE (-2825 4225);
FORCEPROP 1 LAST PATH I120
J 0
(-3150 4350);
DISPLAY 0.936170 (-3150 4350);
PAINT GREEN (-3150 4350);
DISPLAY INVISIBLE (-3150 4350);
FORCEADD TAP..6
(-3150 4300);
FORCEPROP 3 LASTPIN (-3100 4300) SIG_NAME M_F_MA<8>
J 0
(-3090 4310);
DISPLAY 0.659574 (-3090 4310);
PAINT MONO (-3090 4310);
DISPLAY INVISIBLE (-3090 4310);
FORCEPROP 1 LASTPIN (-3100 4300) BN 8
J 0
(-3150 4310);
DISPLAY 0.617021 (-3150 4310);
PAINT PINK (-3150 4310);
FORCEPROP 2 LAST CDS_LIB mstr_standard
J 2
(-3150 4300);
DISPLAY 0.787234 (-3150 4300);
PAINT MONO (-3150 4300);
DISPLAY INVISIBLE (-3150 4300);
FORCEPROP 1 LAST BODY_TYPE PLUMBING
J 0
(-3150 4250);
DISPLAY 1.234043 (-3150 4250);
PAINT GREEN (-3150 4250);
DISPLAY INVISIBLE (-3150 4250);
FORCEPROP 1 LAST HDL_TAP TRUE
J 0
(-2825 4175);
DISPLAY 1.234043 (-2825 4175);
PAINT GREEN (-2825 4175);
DISPLAY INVISIBLE (-2825 4175);
FORCEPROP 1 LAST PATH I121
J 0
(-3150 4300);
DISPLAY 0.936170 (-3150 4300);
PAINT GREEN (-3150 4300);
DISPLAY INVISIBLE (-3150 4300);
FORCEADD TAP..6
(-3150 4250);
FORCEPROP 3 LASTPIN (-3100 4250) SIG_NAME M_F_MA<7>
J 0
(-3090 4260);
DISPLAY 0.659574 (-3090 4260);
PAINT MONO (-3090 4260);
DISPLAY INVISIBLE (-3090 4260);
FORCEPROP 1 LASTPIN (-3100 4250) BN 7
J 0
(-3150 4260);
DISPLAY 0.617021 (-3150 4260);
PAINT PINK (-3150 4260);
FORCEPROP 2 LAST CDS_LIB mstr_standard
J 2
(-3150 4250);
DISPLAY 0.787234 (-3150 4250);
PAINT MONO (-3150 4250);
DISPLAY INVISIBLE (-3150 4250);
FORCEPROP 1 LAST BODY_TYPE PLUMBING
J 0
(-3150 4200);
DISPLAY 1.234043 (-3150 4200);
PAINT GREEN (-3150 4200);
DISPLAY INVISIBLE (-3150 4200);
FORCEPROP 1 LAST HDL_TAP TRUE
J 0
(-2825 4125);
DISPLAY 1.234043 (-2825 4125);
PAINT GREEN (-2825 4125);
DISPLAY INVISIBLE (-2825 4125);
FORCEPROP 1 LAST PATH I122
J 0
(-3150 4250);
DISPLAY 0.936170 (-3150 4250);
PAINT GREEN (-3150 4250);
DISPLAY INVISIBLE (-3150 4250);
FORCEADD TAP..6
(-3150 4200);
FORCEPROP 3 LASTPIN (-3100 4200) SIG_NAME M_F_MA<6>
J 0
(-3090 4210);
DISPLAY 0.659574 (-3090 4210);
PAINT MONO (-3090 4210);
DISPLAY INVISIBLE (-3090 4210);
FORCEPROP 1 LASTPIN (-3100 4200) BN 6
J 0
(-3150 4210);
DISPLAY 0.617021 (-3150 4210);
PAINT PINK (-3150 4210);
FORCEPROP 2 LAST CDS_LIB mstr_standard
J 2
(-3150 4200);
DISPLAY 0.787234 (-3150 4200);
PAINT MONO (-3150 4200);
DISPLAY INVISIBLE (-3150 4200);
FORCEPROP 1 LAST BODY_TYPE PLUMBING
J 0
(-3150 4150);
DISPLAY 1.234043 (-3150 4150);
PAINT GREEN (-3150 4150);
DISPLAY INVISIBLE (-3150 4150);
FORCEPROP 1 LAST HDL_TAP TRUE
J 0
(-2825 4075);
DISPLAY 1.234043 (-2825 4075);
PAINT GREEN (-2825 4075);
DISPLAY INVISIBLE (-2825 4075);
FORCEPROP 1 LAST PATH I123
J 0
(-3150 4200);
DISPLAY 0.936170 (-3150 4200);
PAINT GREEN (-3150 4200);
DISPLAY INVISIBLE (-3150 4200);
FORCEADD TAP..6
(-3150 4150);
FORCEPROP 3 LASTPIN (-3100 4150) SIG_NAME M_F_MA<5>
J 0
(-3090 4160);
DISPLAY 0.659574 (-3090 4160);
PAINT MONO (-3090 4160);
DISPLAY INVISIBLE (-3090 4160);
FORCEPROP 1 LASTPIN (-3100 4150) BN 5
J 0
(-3150 4160);
DISPLAY 0.617021 (-3150 4160);
PAINT PINK (-3150 4160);
FORCEPROP 2 LAST CDS_LIB mstr_standard
J 2
(-3150 4150);
DISPLAY 0.787234 (-3150 4150);
PAINT MONO (-3150 4150);
DISPLAY INVISIBLE (-3150 4150);
FORCEPROP 1 LAST BODY_TYPE PLUMBING
J 0
(-3150 4100);
DISPLAY 1.234043 (-3150 4100);
PAINT GREEN (-3150 4100);
DISPLAY INVISIBLE (-3150 4100);
FORCEPROP 1 LAST HDL_TAP TRUE
J 0
(-2825 4025);
DISPLAY 1.234043 (-2825 4025);
PAINT GREEN (-2825 4025);
DISPLAY INVISIBLE (-2825 4025);
FORCEPROP 1 LAST PATH I124
J 0
(-3150 4150);
DISPLAY 0.936170 (-3150 4150);
PAINT GREEN (-3150 4150);
DISPLAY INVISIBLE (-3150 4150);
FORCEADD TAP..6
(-3150 4100);
FORCEPROP 3 LASTPIN (-3100 4100) SIG_NAME M_F_MA<4>
J 0
(-3090 4110);
DISPLAY 0.659574 (-3090 4110);
PAINT MONO (-3090 4110);
DISPLAY INVISIBLE (-3090 4110);
FORCEPROP 1 LASTPIN (-3100 4100) BN 4
J 0
(-3150 4110);
DISPLAY 0.617021 (-3150 4110);
PAINT PINK (-3150 4110);
FORCEPROP 2 LAST CDS_LIB mstr_standard
J 2
(-3150 4100);
DISPLAY 0.787234 (-3150 4100);
PAINT MONO (-3150 4100);
DISPLAY INVISIBLE (-3150 4100);
FORCEPROP 1 LAST BODY_TYPE PLUMBING
J 0
(-3150 4050);
DISPLAY 1.234043 (-3150 4050);
PAINT GREEN (-3150 4050);
DISPLAY INVISIBLE (-3150 4050);
FORCEPROP 1 LAST HDL_TAP TRUE
J 0
(-2825 3975);
DISPLAY 1.234043 (-2825 3975);
PAINT GREEN (-2825 3975);
DISPLAY INVISIBLE (-2825 3975);
FORCEPROP 1 LAST PATH I125
J 0
(-3150 4100);
DISPLAY 0.936170 (-3150 4100);
PAINT GREEN (-3150 4100);
DISPLAY INVISIBLE (-3150 4100);
FORCEADD TAP..6
(-3150 4000);
FORCEPROP 3 LASTPIN (-3100 4000) SIG_NAME M_F_MA<2>
J 0
(-3090 4010);
DISPLAY 0.659574 (-3090 4010);
PAINT MONO (-3090 4010);
DISPLAY INVISIBLE (-3090 4010);
FORCEPROP 1 LASTPIN (-3100 4000) BN 2
J 0
(-3150 4010);
DISPLAY 0.617021 (-3150 4010);
PAINT PINK (-3150 4010);
FORCEPROP 2 LAST CDS_LIB mstr_standard
J 2
(-3150 4000);
DISPLAY 0.787234 (-3150 4000);
PAINT MONO (-3150 4000);
DISPLAY INVISIBLE (-3150 4000);
FORCEPROP 1 LAST BODY_TYPE PLUMBING
J 0
(-3150 3950);
DISPLAY 1.234043 (-3150 3950);
PAINT GREEN (-3150 3950);
DISPLAY INVISIBLE (-3150 3950);
FORCEPROP 1 LAST HDL_TAP TRUE
J 0
(-2825 3875);
DISPLAY 1.234043 (-2825 3875);
PAINT GREEN (-2825 3875);
DISPLAY INVISIBLE (-2825 3875);
FORCEPROP 1 LAST PATH I126
J 0
(-3150 4000);
DISPLAY 0.936170 (-3150 4000);
PAINT GREEN (-3150 4000);
DISPLAY INVISIBLE (-3150 4000);
FORCEADD TAP..6
(-3150 4050);
FORCEPROP 3 LASTPIN (-3100 4050) SIG_NAME M_F_MA<3>
J 0
(-3090 4060);
DISPLAY 0.659574 (-3090 4060);
PAINT MONO (-3090 4060);
DISPLAY INVISIBLE (-3090 4060);
FORCEPROP 1 LASTPIN (-3100 4050) BN 3
J 0
(-3150 4060);
DISPLAY 0.617021 (-3150 4060);
PAINT PINK (-3150 4060);
FORCEPROP 2 LAST CDS_LIB mstr_standard
J 2
(-3150 4050);
DISPLAY 0.787234 (-3150 4050);
PAINT MONO (-3150 4050);
DISPLAY INVISIBLE (-3150 4050);
FORCEPROP 1 LAST BODY_TYPE PLUMBING
J 0
(-3150 4000);
DISPLAY 1.234043 (-3150 4000);
PAINT GREEN (-3150 4000);
DISPLAY INVISIBLE (-3150 4000);
FORCEPROP 1 LAST HDL_TAP TRUE
J 0
(-2825 3925);
DISPLAY 1.234043 (-2825 3925);
PAINT GREEN (-2825 3925);
DISPLAY INVISIBLE (-2825 3925);
FORCEPROP 1 LAST PATH I127
J 0
(-3150 4050);
DISPLAY 0.936170 (-3150 4050);
PAINT GREEN (-3150 4050);
DISPLAY INVISIBLE (-3150 4050);
FORCEADD TAP..6
(-3150 3950);
FORCEPROP 3 LASTPIN (-3100 3950) SIG_NAME M_F_MA<1>
J 0
(-3090 3960);
DISPLAY 0.659574 (-3090 3960);
PAINT MONO (-3090 3960);
DISPLAY INVISIBLE (-3090 3960);
FORCEPROP 1 LASTPIN (-3100 3950) BN 1
J 0
(-3150 3960);
DISPLAY 0.617021 (-3150 3960);
PAINT PINK (-3150 3960);
FORCEPROP 2 LAST CDS_LIB mstr_standard
J 2
(-3150 3950);
DISPLAY 0.787234 (-3150 3950);
PAINT MONO (-3150 3950);
DISPLAY INVISIBLE (-3150 3950);
FORCEPROP 1 LAST BODY_TYPE PLUMBING
J 0
(-3150 3900);
DISPLAY 1.234043 (-3150 3900);
PAINT GREEN (-3150 3900);
DISPLAY INVISIBLE (-3150 3900);
FORCEPROP 1 LAST HDL_TAP TRUE
J 0
(-2825 3825);
DISPLAY 1.234043 (-2825 3825);
PAINT GREEN (-2825 3825);
DISPLAY INVISIBLE (-2825 3825);
FORCEPROP 1 LAST PATH I128
J 0
(-3150 3950);
DISPLAY 0.936170 (-3150 3950);
PAINT GREEN (-3150 3950);
DISPLAY INVISIBLE (-3150 3950);
FORCEADD TAP..6
(-3150 3900);
FORCEPROP 3 LASTPIN (-3100 3900) SIG_NAME M_F_MA<0>
J 0
(-3090 3910);
DISPLAY 0.659574 (-3090 3910);
PAINT MONO (-3090 3910);
DISPLAY INVISIBLE (-3090 3910);
FORCEPROP 1 LASTPIN (-3100 3900) BN 0
J 0
(-3150 3910);
DISPLAY 0.617021 (-3150 3910);
PAINT PINK (-3150 3910);
FORCEPROP 2 LAST CDS_LIB mstr_standard
J 2
(-3150 3900);
DISPLAY 0.787234 (-3150 3900);
PAINT MONO (-3150 3900);
DISPLAY INVISIBLE (-3150 3900);
FORCEPROP 1 LAST BODY_TYPE PLUMBING
J 0
(-3150 3850);
DISPLAY 1.234043 (-3150 3850);
PAINT GREEN (-3150 3850);
DISPLAY INVISIBLE (-3150 3850);
FORCEPROP 1 LAST HDL_TAP TRUE
J 0
(-2825 3775);
DISPLAY 1.234043 (-2825 3775);
PAINT GREEN (-2825 3775);
DISPLAY INVISIBLE (-2825 3775);
FORCEPROP 1 LAST PATH I129
J 0
(-3150 3900);
DISPLAY 0.936170 (-3150 3900);
PAINT GREEN (-3150 3900);
DISPLAY INVISIBLE (-3150 3900);
FORCEADD TAP..6
R 2
(700 4550);
FORCEPROP 3 LASTPIN (650 4550) SIG_NAME M_F_DQS_DP<11>
J 0
(660 4560);
DISPLAY 0.659574 (660 4560);
PAINT MONO (660 4560);
DISPLAY INVISIBLE (660 4560);
FORCEPROP 1 LASTPIN (650 4550) BN 11
J 2
(700 4560);
DISPLAY 0.617021 (700 4560);
PAINT PINK (700 4560);
FORCEPROP 2 LAST CDS_LIB mstr_standard
J 0
(700 4550);
DISPLAY 0.787234 (700 4550);
PAINT MONO (700 4550);
DISPLAY INVISIBLE (700 4550);
FORCEPROP 1 LAST BODY_TYPE PLUMBING
J 2
(700 4500);
DISPLAY 1.234043 (700 4500);
PAINT GREEN (700 4500);
DISPLAY INVISIBLE (700 4500);
FORCEPROP 1 LAST HDL_TAP TRUE
J 2
(375 4425);
DISPLAY 1.234043 (375 4425);
PAINT GREEN (375 4425);
DISPLAY INVISIBLE (375 4425);
FORCEPROP 1 LAST PATH I13
J 2
(700 4550);
DISPLAY 0.936170 (700 4550);
PAINT GREEN (700 4550);
DISPLAY INVISIBLE (700 4550);
FORCEADD TAP..6
(-3150 3800);
FORCEPROP 3 LASTPIN (-3100 3800) SIG_NAME M_F_BA<1>
J 0
(-3090 3810);
DISPLAY 0.659574 (-3090 3810);
PAINT MONO (-3090 3810);
DISPLAY INVISIBLE (-3090 3810);
FORCEPROP 1 LASTPIN (-3100 3800) BN 1
J 0
(-3150 3810);
DISPLAY 0.617021 (-3150 3810);
PAINT PINK (-3150 3810);
FORCEPROP 2 LAST CDS_LIB mstr_standard
J 0
(-3150 3800);
DISPLAY 0.787234 (-3150 3800);
PAINT MONO (-3150 3800);
DISPLAY INVISIBLE (-3150 3800);
FORCEPROP 1 LAST BODY_TYPE PLUMBING
J 0
(-3150 3750);
DISPLAY 1.234043 (-3150 3750);
PAINT GREEN (-3150 3750);
DISPLAY INVISIBLE (-3150 3750);
FORCEPROP 1 LAST HDL_TAP TRUE
J 0
(-2825 3675);
DISPLAY 1.234043 (-2825 3675);
PAINT GREEN (-2825 3675);
DISPLAY INVISIBLE (-2825 3675);
FORCEPROP 1 LAST PATH I130
J 0
(-3150 3800);
DISPLAY 0.936170 (-3150 3800);
PAINT GREEN (-3150 3800);
DISPLAY INVISIBLE (-3150 3800);
FORCEADD OFFPAGE..1
(-3775 4800);
FORCEPROP 2 LAST $XR0 28 
J 0
(-3996 4800);
DISPLAY 0.638298 (-3996 4800);
PAINT MONO (-3996 4800);
FORCEPROP 2 LAST $XR1 53 
J 0
(-4086 4800);
DISPLAY 0.638298 (-4086 4800);
PAINT MONO (-4086 4800);
FORCEPROP 2 LAST CDS_LIB mstr_standard
J 0
(-3775 4800);
DISPLAY 0.787234 (-3775 4800);
PAINT MONO (-3775 4800);
DISPLAY INVISIBLE (-3775 4800);
FORCEPROP 1 LAST OFFPAGE TRUE
J 0
(-3450 4675);
DISPLAY 0.936170 (-3450 4675);
PAINT GREEN (-3450 4675);
DISPLAY INVISIBLE (-3450 4675);
FORCEPROP 1 LAST COMMENT_BODY TRUE
J 0
(-3650 4700);
DISPLAY 0.936170 (-3650 4700);
PAINT GREEN (-3650 4700);
DISPLAY INVISIBLE (-3650 4700);
FORCEPROP 2 LAST PATH I131
J 0
(-3725 4875);
DISPLAY 0.787234 (-3725 4875);
PAINT MONO (-3725 4875);
DISPLAY INVISIBLE (-3725 4875);
FORCEADD OFFPAGE..1
(-3800 3900);
FORCEPROP 2 LAST $XR0 28 
J 0
(-4051 3900);
DISPLAY 0.638298 (-4051 3900);
PAINT MONO (-4051 3900);
FORCEPROP 2 LAST $XR1 53 
J 0
(-4141 3900);
DISPLAY 0.638298 (-4141 3900);
PAINT MONO (-4141 3900);
FORCEPROP 2 LAST CDS_LIB mstr_standard
J 0
(-3800 3900);
DISPLAY 0.787234 (-3800 3900);
PAINT MONO (-3800 3900);
DISPLAY INVISIBLE (-3800 3900);
FORCEPROP 1 LAST OFFPAGE TRUE
J 0
(-3475 3775);
DISPLAY 0.936170 (-3475 3775);
PAINT GREEN (-3475 3775);
DISPLAY INVISIBLE (-3475 3775);
FORCEPROP 1 LAST COMMENT_BODY TRUE
J 0
(-3675 3800);
DISPLAY 0.936170 (-3675 3800);
PAINT GREEN (-3675 3800);
DISPLAY INVISIBLE (-3675 3800);
FORCEPROP 2 LAST PATH I132
J 0
(-3750 3975);
DISPLAY 0.787234 (-3750 3975);
PAINT MONO (-3750 3975);
DISPLAY INVISIBLE (-3750 3975);
FORCEADD TAP..6
(-3150 3750);
FORCEPROP 3 LASTPIN (-3100 3750) SIG_NAME M_F_BA<0>
J 0
(-3090 3760);
DISPLAY 0.659574 (-3090 3760);
PAINT MONO (-3090 3760);
DISPLAY INVISIBLE (-3090 3760);
FORCEPROP 1 LASTPIN (-3100 3750) BN 0
J 0
(-3150 3760);
DISPLAY 0.617021 (-3150 3760);
PAINT PINK (-3150 3760);
FORCEPROP 2 LAST CDS_LIB mstr_standard
J 0
(-3150 3750);
DISPLAY 0.787234 (-3150 3750);
PAINT MONO (-3150 3750);
DISPLAY INVISIBLE (-3150 3750);
FORCEPROP 1 LAST BODY_TYPE PLUMBING
J 0
(-3150 3700);
DISPLAY 1.234043 (-3150 3700);
PAINT GREEN (-3150 3700);
DISPLAY INVISIBLE (-3150 3700);
FORCEPROP 1 LAST HDL_TAP TRUE
J 0
(-2825 3625);
DISPLAY 1.234043 (-2825 3625);
PAINT GREEN (-2825 3625);
DISPLAY INVISIBLE (-2825 3625);
FORCEPROP 1 LAST PATH I133
J 0
(-3150 3750);
DISPLAY 0.936170 (-3150 3750);
PAINT GREEN (-3150 3750);
DISPLAY INVISIBLE (-3150 3750);
FORCEADD TAP..6
(-3150 3700);
FORCEPROP 3 LASTPIN (-3100 3700) SIG_NAME M_F_BG<1>
J 0
(-3090 3710);
DISPLAY 0.659574 (-3090 3710);
PAINT MONO (-3090 3710);
DISPLAY INVISIBLE (-3090 3710);
FORCEPROP 1 LASTPIN (-3100 3700) BN 1
J 0
(-3150 3710);
DISPLAY 0.617021 (-3150 3710);
PAINT PINK (-3150 3710);
FORCEPROP 2 LAST CDS_LIB mstr_standard
J 0
(-3150 3700);
DISPLAY 0.787234 (-3150 3700);
PAINT MONO (-3150 3700);
DISPLAY INVISIBLE (-3150 3700);
FORCEPROP 1 LAST BODY_TYPE PLUMBING
J 0
(-3150 3650);
DISPLAY 1.234043 (-3150 3650);
PAINT GREEN (-3150 3650);
DISPLAY INVISIBLE (-3150 3650);
FORCEPROP 1 LAST HDL_TAP TRUE
J 0
(-2825 3575);
DISPLAY 1.234043 (-2825 3575);
PAINT GREEN (-2825 3575);
DISPLAY INVISIBLE (-2825 3575);
FORCEPROP 1 LAST PATH I134
J 0
(-3150 3700);
DISPLAY 0.936170 (-3150 3700);
PAINT GREEN (-3150 3700);
DISPLAY INVISIBLE (-3150 3700);
FORCEADD TAP..6
(-3150 3650);
FORCEPROP 3 LASTPIN (-3100 3650) SIG_NAME M_F_BG<0>
J 0
(-3090 3660);
DISPLAY 0.659574 (-3090 3660);
PAINT MONO (-3090 3660);
DISPLAY INVISIBLE (-3090 3660);
FORCEPROP 1 LASTPIN (-3100 3650) BN 0
J 0
(-3150 3660);
DISPLAY 0.617021 (-3150 3660);
PAINT PINK (-3150 3660);
FORCEPROP 2 LAST CDS_LIB mstr_standard
J 0
(-3150 3650);
DISPLAY 0.787234 (-3150 3650);
PAINT MONO (-3150 3650);
DISPLAY INVISIBLE (-3150 3650);
FORCEPROP 1 LAST BODY_TYPE PLUMBING
J 0
(-3150 3600);
DISPLAY 1.234043 (-3150 3600);
PAINT GREEN (-3150 3600);
DISPLAY INVISIBLE (-3150 3600);
FORCEPROP 1 LAST HDL_TAP TRUE
J 0
(-2825 3525);
DISPLAY 1.234043 (-2825 3525);
PAINT GREEN (-2825 3525);
DISPLAY INVISIBLE (-2825 3525);
FORCEPROP 1 LAST PATH I135
J 0
(-3150 3650);
DISPLAY 0.936170 (-3150 3650);
PAINT GREEN (-3150 3650);
DISPLAY INVISIBLE (-3150 3650);
FORCEADD OFFPAGE..1
(-3800 3350);
FORCEPROP 2 LAST $XR0 28 
J 0
(-4051 3350);
DISPLAY 0.638298 (-4051 3350);
PAINT MONO (-4051 3350);
FORCEPROP 2 LAST $XR1 53 
J 0
(-4141 3350);
DISPLAY 0.638298 (-4141 3350);
PAINT MONO (-4141 3350);
FORCEPROP 2 LAST CDS_LIB mstr_standard
J 0
(-3800 3350);
DISPLAY 0.787234 (-3800 3350);
PAINT MONO (-3800 3350);
DISPLAY INVISIBLE (-3800 3350);
FORCEPROP 1 LAST OFFPAGE TRUE
J 0
(-3475 3225);
DISPLAY 0.936170 (-3475 3225);
PAINT GREEN (-3475 3225);
DISPLAY INVISIBLE (-3475 3225);
FORCEPROP 1 LAST COMMENT_BODY TRUE
J 0
(-3675 3250);
DISPLAY 0.936170 (-3675 3250);
PAINT GREEN (-3675 3250);
DISPLAY INVISIBLE (-3675 3250);
FORCEPROP 2 LAST PATH I136
J 0
(-3750 3425);
DISPLAY 0.787234 (-3750 3425);
PAINT MONO (-3750 3425);
DISPLAY INVISIBLE (-3750 3425);
FORCEADD OFFPAGE..1
(-3800 3750);
FORCEPROP 2 LAST $XR0 28 
J 0
(-4051 3750);
DISPLAY 0.638298 (-4051 3750);
PAINT MONO (-4051 3750);
FORCEPROP 2 LAST $XR1 53 
J 0
(-4141 3750);
DISPLAY 0.638298 (-4141 3750);
PAINT MONO (-4141 3750);
FORCEPROP 2 LAST CDS_LIB mstr_standard
J 0
(-3800 3750);
DISPLAY 0.787234 (-3800 3750);
PAINT MONO (-3800 3750);
DISPLAY INVISIBLE (-3800 3750);
FORCEPROP 1 LAST OFFPAGE TRUE
J 0
(-3475 3625);
DISPLAY 0.936170 (-3475 3625);
PAINT GREEN (-3475 3625);
DISPLAY INVISIBLE (-3475 3625);
FORCEPROP 1 LAST COMMENT_BODY TRUE
J 0
(-3675 3650);
DISPLAY 0.936170 (-3675 3650);
PAINT GREEN (-3675 3650);
DISPLAY INVISIBLE (-3675 3650);
FORCEPROP 2 LAST PATH I137
J 0
(-3750 3825);
DISPLAY 0.787234 (-3750 3825);
PAINT MONO (-3750 3825);
DISPLAY INVISIBLE (-3750 3825);
FORCEADD TAP..6
(-3150 2700);
FORCEPROP 3 LASTPIN (-3100 2700) SIG_NAME M_F_ECC<7>
J 0
(-3090 2710);
DISPLAY 0.659574 (-3090 2710);
PAINT MONO (-3090 2710);
DISPLAY INVISIBLE (-3090 2710);
FORCEPROP 1 LASTPIN (-3100 2700) BN 7
J 0
(-3150 2710);
DISPLAY 0.617021 (-3150 2710);
PAINT PINK (-3150 2710);
FORCEPROP 2 LAST CDS_LIB mstr_standard
J 0
(-3150 2700);
DISPLAY 0.787234 (-3150 2700);
PAINT MONO (-3150 2700);
DISPLAY INVISIBLE (-3150 2700);
FORCEPROP 1 LAST BODY_TYPE PLUMBING
J 0
(-3150 2650);
DISPLAY 1.234043 (-3150 2650);
PAINT GREEN (-3150 2650);
DISPLAY INVISIBLE (-3150 2650);
FORCEPROP 1 LAST HDL_TAP TRUE
J 0
(-2825 2575);
DISPLAY 1.234043 (-2825 2575);
PAINT GREEN (-2825 2575);
DISPLAY INVISIBLE (-2825 2575);
FORCEPROP 1 LAST PATH I138
J 0
(-3150 2700);
DISPLAY 0.936170 (-3150 2700);
PAINT GREEN (-3150 2700);
DISPLAY INVISIBLE (-3150 2700);
FORCEADD TAP..6
(-3150 2650);
FORCEPROP 3 LASTPIN (-3100 2650) SIG_NAME M_F_ECC<6>
J 0
(-3090 2660);
DISPLAY 0.659574 (-3090 2660);
PAINT MONO (-3090 2660);
DISPLAY INVISIBLE (-3090 2660);
FORCEPROP 1 LASTPIN (-3100 2650) BN 6
J 0
(-3150 2660);
DISPLAY 0.617021 (-3150 2660);
PAINT PINK (-3150 2660);
FORCEPROP 2 LAST CDS_LIB mstr_standard
J 0
(-3150 2650);
DISPLAY 0.787234 (-3150 2650);
PAINT MONO (-3150 2650);
DISPLAY INVISIBLE (-3150 2650);
FORCEPROP 1 LAST BODY_TYPE PLUMBING
J 0
(-3150 2600);
DISPLAY 1.234043 (-3150 2600);
PAINT GREEN (-3150 2600);
DISPLAY INVISIBLE (-3150 2600);
FORCEPROP 1 LAST HDL_TAP TRUE
J 0
(-2825 2525);
DISPLAY 1.234043 (-2825 2525);
PAINT GREEN (-2825 2525);
DISPLAY INVISIBLE (-2825 2525);
FORCEPROP 1 LAST PATH I139
J 0
(-3150 2650);
DISPLAY 0.936170 (-3150 2650);
PAINT GREEN (-3150 2650);
DISPLAY INVISIBLE (-3150 2650);
FORCEADD TAP..6
R 2
(700 4650);
FORCEPROP 3 LASTPIN (650 4650) SIG_NAME M_F_DQS_DP<12>
J 0
(660 4660);
DISPLAY 0.659574 (660 4660);
PAINT MONO (660 4660);
DISPLAY INVISIBLE (660 4660);
FORCEPROP 1 LASTPIN (650 4650) BN 12
J 2
(700 4660);
DISPLAY 0.617021 (700 4660);
PAINT PINK (700 4660);
FORCEPROP 2 LAST CDS_LIB mstr_standard
J 0
(700 4650);
DISPLAY 0.787234 (700 4650);
PAINT MONO (700 4650);
DISPLAY INVISIBLE (700 4650);
FORCEPROP 1 LAST BODY_TYPE PLUMBING
J 2
(700 4600);
DISPLAY 1.234043 (700 4600);
PAINT GREEN (700 4600);
DISPLAY INVISIBLE (700 4600);
FORCEPROP 1 LAST HDL_TAP TRUE
J 2
(375 4525);
DISPLAY 1.234043 (375 4525);
PAINT GREEN (375 4525);
DISPLAY INVISIBLE (375 4525);
FORCEPROP 1 LAST PATH I14
J 2
(700 4650);
DISPLAY 0.936170 (700 4650);
PAINT GREEN (700 4650);
DISPLAY INVISIBLE (700 4650);
FORCEADD TAP..6
(-3150 2600);
FORCEPROP 3 LASTPIN (-3100 2600) SIG_NAME M_F_ECC<5>
J 0
(-3090 2610);
DISPLAY 0.659574 (-3090 2610);
PAINT MONO (-3090 2610);
DISPLAY INVISIBLE (-3090 2610);
FORCEPROP 1 LASTPIN (-3100 2600) BN 5
J 0
(-3150 2610);
DISPLAY 0.617021 (-3150 2610);
PAINT PINK (-3150 2610);
FORCEPROP 2 LAST CDS_LIB mstr_standard
J 0
(-3150 2600);
DISPLAY 0.787234 (-3150 2600);
PAINT MONO (-3150 2600);
DISPLAY INVISIBLE (-3150 2600);
FORCEPROP 1 LAST BODY_TYPE PLUMBING
J 0
(-3150 2550);
DISPLAY 1.234043 (-3150 2550);
PAINT GREEN (-3150 2550);
DISPLAY INVISIBLE (-3150 2550);
FORCEPROP 1 LAST HDL_TAP TRUE
J 0
(-2825 2475);
DISPLAY 1.234043 (-2825 2475);
PAINT GREEN (-2825 2475);
DISPLAY INVISIBLE (-2825 2475);
FORCEPROP 1 LAST PATH I140
J 0
(-3150 2600);
DISPLAY 0.936170 (-3150 2600);
PAINT GREEN (-3150 2600);
DISPLAY INVISIBLE (-3150 2600);
FORCEADD TAP..6
(-3150 2550);
FORCEPROP 3 LASTPIN (-3100 2550) SIG_NAME M_F_ECC<4>
J 0
(-3090 2560);
DISPLAY 0.659574 (-3090 2560);
PAINT MONO (-3090 2560);
DISPLAY INVISIBLE (-3090 2560);
FORCEPROP 1 LASTPIN (-3100 2550) BN 4
J 0
(-3150 2560);
DISPLAY 0.617021 (-3150 2560);
PAINT PINK (-3150 2560);
FORCEPROP 2 LAST CDS_LIB mstr_standard
J 0
(-3150 2550);
DISPLAY 0.787234 (-3150 2550);
PAINT MONO (-3150 2550);
DISPLAY INVISIBLE (-3150 2550);
FORCEPROP 1 LAST BODY_TYPE PLUMBING
J 0
(-3150 2500);
DISPLAY 1.234043 (-3150 2500);
PAINT GREEN (-3150 2500);
DISPLAY INVISIBLE (-3150 2500);
FORCEPROP 1 LAST HDL_TAP TRUE
J 0
(-2825 2425);
DISPLAY 1.234043 (-2825 2425);
PAINT GREEN (-2825 2425);
DISPLAY INVISIBLE (-2825 2425);
FORCEPROP 1 LAST PATH I141
J 0
(-3150 2550);
DISPLAY 0.936170 (-3150 2550);
PAINT GREEN (-3150 2550);
DISPLAY INVISIBLE (-3150 2550);
FORCEADD TAP..6
(-3150 2500);
FORCEPROP 3 LASTPIN (-3100 2500) SIG_NAME M_F_ECC<3>
J 0
(-3090 2510);
DISPLAY 0.659574 (-3090 2510);
PAINT MONO (-3090 2510);
DISPLAY INVISIBLE (-3090 2510);
FORCEPROP 1 LASTPIN (-3100 2500) BN 3
J 0
(-3150 2510);
DISPLAY 0.617021 (-3150 2510);
PAINT PINK (-3150 2510);
FORCEPROP 2 LAST CDS_LIB mstr_standard
J 0
(-3150 2500);
DISPLAY 0.787234 (-3150 2500);
PAINT MONO (-3150 2500);
DISPLAY INVISIBLE (-3150 2500);
FORCEPROP 1 LAST BODY_TYPE PLUMBING
J 0
(-3150 2450);
DISPLAY 1.234043 (-3150 2450);
PAINT GREEN (-3150 2450);
DISPLAY INVISIBLE (-3150 2450);
FORCEPROP 1 LAST HDL_TAP TRUE
J 0
(-2825 2375);
DISPLAY 1.234043 (-2825 2375);
PAINT GREEN (-2825 2375);
DISPLAY INVISIBLE (-2825 2375);
FORCEPROP 1 LAST PATH I142
J 0
(-3150 2500);
DISPLAY 0.936170 (-3150 2500);
PAINT GREEN (-3150 2500);
DISPLAY INVISIBLE (-3150 2500);
FORCEADD TAP..6
(-3150 2450);
FORCEPROP 3 LASTPIN (-3100 2450) SIG_NAME M_F_ECC<2>
J 0
(-3090 2460);
DISPLAY 0.659574 (-3090 2460);
PAINT MONO (-3090 2460);
DISPLAY INVISIBLE (-3090 2460);
FORCEPROP 1 LASTPIN (-3100 2450) BN 2
J 0
(-3150 2460);
DISPLAY 0.617021 (-3150 2460);
PAINT PINK (-3150 2460);
FORCEPROP 2 LAST CDS_LIB mstr_standard
J 0
(-3150 2450);
DISPLAY 0.787234 (-3150 2450);
PAINT MONO (-3150 2450);
DISPLAY INVISIBLE (-3150 2450);
FORCEPROP 1 LAST BODY_TYPE PLUMBING
J 0
(-3150 2400);
DISPLAY 1.234043 (-3150 2400);
PAINT GREEN (-3150 2400);
DISPLAY INVISIBLE (-3150 2400);
FORCEPROP 1 LAST HDL_TAP TRUE
J 0
(-2825 2325);
DISPLAY 1.234043 (-2825 2325);
PAINT GREEN (-2825 2325);
DISPLAY INVISIBLE (-2825 2325);
FORCEPROP 1 LAST PATH I143
J 0
(-3150 2450);
DISPLAY 0.936170 (-3150 2450);
PAINT GREEN (-3150 2450);
DISPLAY INVISIBLE (-3150 2450);
FORCEADD TAP..6
(-3150 2400);
FORCEPROP 3 LASTPIN (-3100 2400) SIG_NAME M_F_ECC<1>
J 0
(-3090 2410);
DISPLAY 0.659574 (-3090 2410);
PAINT MONO (-3090 2410);
DISPLAY INVISIBLE (-3090 2410);
FORCEPROP 1 LASTPIN (-3100 2400) BN 1
J 0
(-3150 2410);
DISPLAY 0.617021 (-3150 2410);
PAINT PINK (-3150 2410);
FORCEPROP 2 LAST CDS_LIB mstr_standard
J 0
(-3150 2400);
DISPLAY 0.787234 (-3150 2400);
PAINT MONO (-3150 2400);
DISPLAY INVISIBLE (-3150 2400);
FORCEPROP 1 LAST BODY_TYPE PLUMBING
J 0
(-3150 2350);
DISPLAY 1.234043 (-3150 2350);
PAINT GREEN (-3150 2350);
DISPLAY INVISIBLE (-3150 2350);
FORCEPROP 1 LAST HDL_TAP TRUE
J 0
(-2825 2275);
DISPLAY 1.234043 (-2825 2275);
PAINT GREEN (-2825 2275);
DISPLAY INVISIBLE (-2825 2275);
FORCEPROP 1 LAST PATH I144
J 0
(-3150 2400);
DISPLAY 0.936170 (-3150 2400);
PAINT GREEN (-3150 2400);
DISPLAY INVISIBLE (-3150 2400);
FORCEADD TAP..6
(-3150 2350);
FORCEPROP 3 LASTPIN (-3100 2350) SIG_NAME M_F_ECC<0>
J 0
(-3090 2360);
DISPLAY 0.659574 (-3090 2360);
PAINT MONO (-3090 2360);
DISPLAY INVISIBLE (-3090 2360);
FORCEPROP 1 LASTPIN (-3100 2350) BN 0
J 0
(-3150 2360);
DISPLAY 0.617021 (-3150 2360);
PAINT PINK (-3150 2360);
FORCEPROP 2 LAST CDS_LIB mstr_standard
J 0
(-3150 2350);
DISPLAY 0.787234 (-3150 2350);
PAINT MONO (-3150 2350);
DISPLAY INVISIBLE (-3150 2350);
FORCEPROP 1 LAST BODY_TYPE PLUMBING
J 0
(-3150 2300);
DISPLAY 1.234043 (-3150 2300);
PAINT GREEN (-3150 2300);
DISPLAY INVISIBLE (-3150 2300);
FORCEPROP 1 LAST HDL_TAP TRUE
J 0
(-2825 2225);
DISPLAY 1.234043 (-2825 2225);
PAINT GREEN (-2825 2225);
DISPLAY INVISIBLE (-2825 2225);
FORCEPROP 1 LAST PATH I145
J 0
(-3150 2350);
DISPLAY 0.936170 (-3150 2350);
PAINT GREEN (-3150 2350);
DISPLAY INVISIBLE (-3150 2350);
FORCEADD OFFPAGE..1
(-3800 2700);
FORCEPROP 2 LAST $XR0 28 
J 0
(-4051 2700);
DISPLAY 0.638298 (-4051 2700);
PAINT MONO (-4051 2700);
FORCEPROP 2 LAST $XR1 53 
J 0
(-4141 2700);
DISPLAY 0.638298 (-4141 2700);
PAINT MONO (-4141 2700);
FORCEPROP 2 LAST CDS_LIB mstr_standard
J 0
(-3800 2700);
DISPLAY 0.787234 (-3800 2700);
PAINT MONO (-3800 2700);
DISPLAY INVISIBLE (-3800 2700);
FORCEPROP 1 LAST OFFPAGE TRUE
J 0
(-3475 2575);
DISPLAY 0.936170 (-3475 2575);
PAINT GREEN (-3475 2575);
DISPLAY INVISIBLE (-3475 2575);
FORCEPROP 1 LAST COMMENT_BODY TRUE
J 0
(-3675 2600);
DISPLAY 0.936170 (-3675 2600);
PAINT GREEN (-3675 2600);
DISPLAY INVISIBLE (-3675 2600);
FORCEPROP 2 LAST PATH I146
J 0
(-3750 2775);
DISPLAY 0.787234 (-3750 2775);
PAINT MONO (-3750 2775);
DISPLAY INVISIBLE (-3750 2775);
FORCEADD OFFPAGE..1
(-3950 2050);
FORCEPROP 2 LAST $XR0 28 
J 0
(-4201 2050);
DISPLAY 0.638298 (-4201 2050);
PAINT MONO (-4201 2050);
FORCEPROP 2 LAST $XR1 53 
J 0
(-4291 2050);
DISPLAY 0.638298 (-4291 2050);
PAINT MONO (-4291 2050);
FORCEPROP 2 LAST CDS_LIB mstr_standard
J 0
(-3950 2050);
DISPLAY 0.787234 (-3950 2050);
PAINT MONO (-3950 2050);
DISPLAY INVISIBLE (-3950 2050);
FORCEPROP 1 LAST OFFPAGE TRUE
J 0
(-3625 1925);
DISPLAY 0.936170 (-3625 1925);
PAINT GREEN (-3625 1925);
DISPLAY INVISIBLE (-3625 1925);
FORCEPROP 1 LAST COMMENT_BODY TRUE
J 0
(-3825 1950);
DISPLAY 0.936170 (-3825 1950);
PAINT GREEN (-3825 1950);
DISPLAY INVISIBLE (-3825 1950);
FORCEPROP 2 LAST PATH I147
J 0
(-3900 2125);
DISPLAY 0.787234 (-3900 2125);
PAINT MONO (-3900 2125);
DISPLAY INVISIBLE (-3900 2125);
FORCEADD OFFPAGE..5
(-3975 2100);
FORCEPROP 2 LAST $XR0 53 
J 0
(-4229 2100);
DISPLAY 0.638298 (-4229 2100);
PAINT MONO (-4229 2100);
FORCEPROP 2 LAST $XR1 28 
J 0
(-4319 2100);
DISPLAY 0.638298 (-4319 2100);
PAINT MONO (-4319 2100);
FORCEPROP 2 LAST CDS_LIB mstr_standard
J 0
(-3975 2100);
DISPLAY 0.787234 (-3975 2100);
PAINT MONO (-3975 2100);
DISPLAY INVISIBLE (-3975 2100);
FORCEPROP 1 LAST OFFPAGE TRUE
J 0
(-3650 1975);
DISPLAY 1.404255 (-3650 1975);
PAINT GREEN (-3650 1975);
DISPLAY INVISIBLE (-3650 1975);
FORCEPROP 1 LAST COMMENT_BODY TRUE
J 0
(-3875 2025);
DISPLAY 1.404255 (-3875 2025);
PAINT GREEN (-3875 2025);
DISPLAY INVISIBLE (-3875 2025);
FORCEPROP 2 LAST PATH I148
J 0
(-3925 2175);
DISPLAY 0.787234 (-3925 2175);
PAINT MONO (-3925 2175);
DISPLAY INVISIBLE (-3925 2175);
FORCEADD OFFPAGE..1
(-3800 2650);
FORCEPROP 2 LAST $XR0 21 
J 0
(-4051 2650);
DISPLAY 0.638298 (-4051 2650);
PAINT MONO (-4051 2650);
FORCEPROP 2 LAST $XR1 49 
J 0
(-4141 2650);
DISPLAY 0.638298 (-4141 2650);
PAINT MONO (-4141 2650);
FORCEPROP 2 LAST $XR2 50 
J 0
(-4231 2650);
DISPLAY 0.638298 (-4231 2650);
PAINT MONO (-4231 2650);
FORCEPROP 2 LAST $XR3 51 
J 0
(-4321 2650);
DISPLAY 0.638298 (-4321 2650);
PAINT MONO (-4321 2650);
FORCEPROP 2 LAST $XR4 52 
J 0
(-4411 2650);
DISPLAY 0.638298 (-4411 2650);
PAINT MONO (-4411 2650);
FORCEPROP 2 LAST $XR5 53 
J 0
(-4501 2650);
DISPLAY 0.638298 (-4501 2650);
PAINT MONO (-4501 2650);
FORCEPROP 2 LAST CDS_LIB mstr_standard
J 0
(-3800 2650);
DISPLAY 0.787234 (-3800 2650);
PAINT MONO (-3800 2650);
DISPLAY INVISIBLE (-3800 2650);
FORCEPROP 1 LAST OFFPAGE TRUE
J 0
(-3475 2525);
DISPLAY 0.936170 (-3475 2525);
PAINT GREEN (-3475 2525);
DISPLAY INVISIBLE (-3475 2525);
FORCEPROP 1 LAST COMMENT_BODY TRUE
J 0
(-3675 2550);
DISPLAY 0.936170 (-3675 2550);
PAINT GREEN (-3675 2550);
DISPLAY INVISIBLE (-3675 2550);
FORCEPROP 2 LAST PATH I149
J 0
(-3750 2725);
DISPLAY 0.787234 (-3750 2725);
PAINT MONO (-3750 2725);
DISPLAY INVISIBLE (-3750 2725);
FORCEADD TAP..6
R 2
(700 4750);
FORCEPROP 3 LASTPIN (650 4750) SIG_NAME M_F_DQS_DP<13>
J 0
(660 4760);
DISPLAY 0.659574 (660 4760);
PAINT MONO (660 4760);
DISPLAY INVISIBLE (660 4760);
FORCEPROP 1 LASTPIN (650 4750) BN 13
J 2
(700 4760);
DISPLAY 0.617021 (700 4760);
PAINT PINK (700 4760);
FORCEPROP 2 LAST CDS_LIB mstr_standard
J 0
(700 4750);
DISPLAY 0.787234 (700 4750);
PAINT MONO (700 4750);
DISPLAY INVISIBLE (700 4750);
FORCEPROP 1 LAST BODY_TYPE PLUMBING
J 2
(700 4700);
DISPLAY 1.234043 (700 4700);
PAINT GREEN (700 4700);
DISPLAY INVISIBLE (700 4700);
FORCEPROP 1 LAST HDL_TAP TRUE
J 2
(375 4625);
DISPLAY 1.234043 (375 4625);
PAINT GREEN (375 4625);
DISPLAY INVISIBLE (375 4625);
FORCEPROP 1 LAST PATH I15
J 2
(700 4750);
DISPLAY 0.936170 (700 4750);
PAINT GREEN (700 4750);
DISPLAY INVISIBLE (700 4750);
FORCEADD OFFPAGE..6
(-3800 2750);
FORCEPROP 2 LAST $XR0 28 
J 0
(-4049 2750);
DISPLAY 0.638298 (-4049 2750);
PAINT MONO (-4049 2750);
FORCEPROP 2 LAST $XR1 53 
J 0
(-4139 2750);
DISPLAY 0.638298 (-4139 2750);
PAINT MONO (-4139 2750);
FORCEPROP 2 LAST CDS_LIB mstr_standard
J 0
(-3800 2750);
DISPLAY 0.787234 (-3800 2750);
PAINT MONO (-3800 2750);
DISPLAY INVISIBLE (-3800 2750);
FORCEPROP 1 LAST OFFPAGE TRUE
J 0
(-3475 2625);
DISPLAY 0.936170 (-3475 2625);
PAINT GREEN (-3475 2625);
DISPLAY INVISIBLE (-3475 2625);
FORCEPROP 1 LAST COMMENT_BODY TRUE
J 0
(-3700 2675);
DISPLAY 0.936170 (-3700 2675);
PAINT GREEN (-3700 2675);
DISPLAY INVISIBLE (-3700 2675);
FORCEPROP 2 LAST PATH I150
J 0
(-3750 2825);
DISPLAY 0.787234 (-3750 2825);
PAINT MONO (-3750 2825);
DISPLAY INVISIBLE (-3750 2825);
FORCEADD TAP..6
(-3150 3550);
FORCEPROP 3 LASTPIN (-3100 3550) SIG_NAME M_F_CLK_DP<3>
J 0
(-3090 3560);
DISPLAY 0.659574 (-3090 3560);
PAINT MONO (-3090 3560);
DISPLAY INVISIBLE (-3090 3560);
FORCEPROP 1 LASTPIN (-3100 3550) BN 3
J 0
(-3150 3560);
DISPLAY 0.617021 (-3150 3560);
PAINT PINK (-3150 3560);
FORCEPROP 2 LAST CDS_LIB mstr_standard
J 0
(-3150 3550);
DISPLAY 0.787234 (-3150 3550);
PAINT MONO (-3150 3550);
DISPLAY INVISIBLE (-3150 3550);
FORCEPROP 1 LAST BODY_TYPE PLUMBING
J 0
(-3150 3500);
DISPLAY 1.234043 (-3150 3500);
PAINT GREEN (-3150 3500);
DISPLAY INVISIBLE (-3150 3500);
FORCEPROP 1 LAST HDL_TAP TRUE
J 0
(-2825 3425);
DISPLAY 1.234043 (-2825 3425);
PAINT GREEN (-2825 3425);
DISPLAY INVISIBLE (-2825 3425);
FORCEPROP 1 LAST PATH I152
J 0
(-3150 3550);
DISPLAY 0.936170 (-3150 3550);
PAINT GREEN (-3150 3550);
DISPLAY INVISIBLE (-3150 3550);
FORCEADD TAP..6
(-3150 3450);
FORCEPROP 3 LASTPIN (-3100 3450) SIG_NAME M_F_CLK_DP<2>
J 0
(-3090 3460);
DISPLAY 0.659574 (-3090 3460);
PAINT MONO (-3090 3460);
DISPLAY INVISIBLE (-3090 3460);
FORCEPROP 1 LASTPIN (-3100 3450) BN 2
J 0
(-3150 3460);
DISPLAY 0.617021 (-3150 3460);
PAINT PINK (-3150 3460);
FORCEPROP 2 LAST CDS_LIB mstr_standard
J 0
(-3150 3450);
DISPLAY 0.787234 (-3150 3450);
PAINT MONO (-3150 3450);
DISPLAY INVISIBLE (-3150 3450);
FORCEPROP 1 LAST BODY_TYPE PLUMBING
J 0
(-3150 3400);
DISPLAY 1.234043 (-3150 3400);
PAINT GREEN (-3150 3400);
DISPLAY INVISIBLE (-3150 3400);
FORCEPROP 1 LAST HDL_TAP TRUE
J 0
(-2825 3325);
DISPLAY 1.234043 (-2825 3325);
PAINT GREEN (-2825 3325);
DISPLAY INVISIBLE (-2825 3325);
FORCEPROP 1 LAST PATH I153
J 0
(-3150 3450);
DISPLAY 0.936170 (-3150 3450);
PAINT GREEN (-3150 3450);
DISPLAY INVISIBLE (-3150 3450);
FORCEADD TAP..6
(-3350 3500);
FORCEPROP 3 LASTPIN (-3300 3500) SIG_NAME M_F_CLK_DN<3>
J 0
(-3290 3510);
DISPLAY 0.659574 (-3290 3510);
PAINT MONO (-3290 3510);
DISPLAY INVISIBLE (-3290 3510);
FORCEPROP 1 LASTPIN (-3300 3500) BN 3
J 0
(-3350 3510);
DISPLAY 0.617021 (-3350 3510);
PAINT PINK (-3350 3510);
FORCEPROP 2 LAST CDS_LIB mstr_standard
J 0
(-3350 3500);
DISPLAY 0.787234 (-3350 3500);
PAINT MONO (-3350 3500);
DISPLAY INVISIBLE (-3350 3500);
FORCEPROP 1 LAST BODY_TYPE PLUMBING
J 0
(-3350 3450);
DISPLAY 1.234043 (-3350 3450);
PAINT GREEN (-3350 3450);
DISPLAY INVISIBLE (-3350 3450);
FORCEPROP 1 LAST HDL_TAP TRUE
J 0
(-3025 3375);
DISPLAY 1.234043 (-3025 3375);
PAINT GREEN (-3025 3375);
DISPLAY INVISIBLE (-3025 3375);
FORCEPROP 1 LAST PATH I154
J 0
(-3350 3500);
DISPLAY 0.936170 (-3350 3500);
PAINT GREEN (-3350 3500);
DISPLAY INVISIBLE (-3350 3500);
FORCEADD TAP..6
(-3350 3400);
FORCEPROP 3 LASTPIN (-3300 3400) SIG_NAME M_F_CLK_DN<2>
J 0
(-3290 3410);
DISPLAY 0.659574 (-3290 3410);
PAINT MONO (-3290 3410);
DISPLAY INVISIBLE (-3290 3410);
FORCEPROP 1 LASTPIN (-3300 3400) BN 2
J 0
(-3350 3410);
DISPLAY 0.617021 (-3350 3410);
PAINT PINK (-3350 3410);
FORCEPROP 2 LAST CDS_LIB mstr_standard
J 0
(-3350 3400);
DISPLAY 0.787234 (-3350 3400);
PAINT MONO (-3350 3400);
DISPLAY INVISIBLE (-3350 3400);
FORCEPROP 1 LAST BODY_TYPE PLUMBING
J 0
(-3350 3350);
DISPLAY 1.234043 (-3350 3350);
PAINT GREEN (-3350 3350);
DISPLAY INVISIBLE (-3350 3350);
FORCEPROP 1 LAST HDL_TAP TRUE
J 0
(-3025 3275);
DISPLAY 1.234043 (-3025 3275);
PAINT GREEN (-3025 3275);
DISPLAY INVISIBLE (-3025 3275);
FORCEPROP 1 LAST PATH I155
J 0
(-3350 3400);
DISPLAY 0.936170 (-3350 3400);
PAINT GREEN (-3350 3400);
DISPLAY INVISIBLE (-3350 3400);
FORCEADD OFFPAGE..1
(-3850 3550);
FORCEPROP 2 LAST $XR0 28 
J 0
(-4101 3550);
DISPLAY 0.638298 (-4101 3550);
PAINT MONO (-4101 3550);
FORCEPROP 2 LAST $XR1 53 
J 0
(-4191 3550);
DISPLAY 0.638298 (-4191 3550);
PAINT MONO (-4191 3550);
FORCEPROP 2 LAST CDS_LIB mstr_standard
J 0
(-3850 3550);
DISPLAY 0.787234 (-3850 3550);
PAINT MONO (-3850 3550);
DISPLAY INVISIBLE (-3850 3550);
FORCEPROP 1 LAST OFFPAGE TRUE
J 0
(-3525 3425);
DISPLAY 0.936170 (-3525 3425);
PAINT GREEN (-3525 3425);
DISPLAY INVISIBLE (-3525 3425);
FORCEPROP 1 LAST COMMENT_BODY TRUE
J 0
(-3725 3450);
DISPLAY 0.936170 (-3725 3450);
PAINT GREEN (-3725 3450);
DISPLAY INVISIBLE (-3725 3450);
FORCEPROP 2 LAST PATH I156
J 0
(-3800 3625);
DISPLAY 0.787234 (-3800 3625);
PAINT MONO (-3800 3625);
DISPLAY INVISIBLE (-3800 3625);
FORCEADD OFFPAGE..1
(-3850 3600);
FORCEPROP 2 LAST $XR0 28 
J 0
(-4101 3600);
DISPLAY 0.638298 (-4101 3600);
PAINT MONO (-4101 3600);
FORCEPROP 2 LAST $XR1 53 
J 0
(-4191 3600);
DISPLAY 0.638298 (-4191 3600);
PAINT MONO (-4191 3600);
FORCEPROP 2 LAST CDS_LIB mstr_standard
J 0
(-3850 3600);
DISPLAY 0.787234 (-3850 3600);
PAINT MONO (-3850 3600);
DISPLAY INVISIBLE (-3850 3600);
FORCEPROP 1 LAST OFFPAGE TRUE
J 0
(-3525 3475);
DISPLAY 0.936170 (-3525 3475);
PAINT GREEN (-3525 3475);
DISPLAY INVISIBLE (-3525 3475);
FORCEPROP 1 LAST COMMENT_BODY TRUE
J 0
(-3725 3500);
DISPLAY 0.936170 (-3725 3500);
PAINT GREEN (-3725 3500);
DISPLAY INVISIBLE (-3725 3500);
FORCEPROP 2 LAST PATH I157
J 0
(-3800 3675);
DISPLAY 0.787234 (-3800 3675);
PAINT MONO (-3800 3675);
DISPLAY INVISIBLE (-3800 3675);
FORCEADD TAP..6
(-3150 3250);
FORCEPROP 3 LASTPIN (-3100 3250) SIG_NAME M_F_CS_N<7>
J 0
(-3090 3260);
DISPLAY 0.659574 (-3090 3260);
PAINT MONO (-3090 3260);
DISPLAY INVISIBLE (-3090 3260);
FORCEPROP 1 LASTPIN (-3100 3250) BN 7
J 0
(-3150 3260);
DISPLAY 0.617021 (-3150 3260);
PAINT PINK (-3150 3260);
FORCEPROP 2 LAST CDS_LIB mstr_standard
J 0
(-3150 3250);
DISPLAY 0.787234 (-3150 3250);
PAINT MONO (-3150 3250);
DISPLAY INVISIBLE (-3150 3250);
FORCEPROP 1 LAST BODY_TYPE PLUMBING
J 0
(-3150 3200);
DISPLAY 1.234043 (-3150 3200);
PAINT GREEN (-3150 3200);
DISPLAY INVISIBLE (-3150 3200);
FORCEPROP 1 LAST HDL_TAP TRUE
J 0
(-2825 3125);
DISPLAY 1.234043 (-2825 3125);
PAINT GREEN (-2825 3125);
DISPLAY INVISIBLE (-2825 3125);
FORCEPROP 1 LAST PATH I158
J 0
(-3150 3250);
DISPLAY 0.936170 (-3150 3250);
PAINT GREEN (-3150 3250);
DISPLAY INVISIBLE (-3150 3250);
FORCEADD TAP..6
(-3150 3200);
FORCEPROP 3 LASTPIN (-3100 3200) SIG_NAME M_F_CS_N<6>
J 0
(-3090 3210);
DISPLAY 0.659574 (-3090 3210);
PAINT MONO (-3090 3210);
DISPLAY INVISIBLE (-3090 3210);
FORCEPROP 1 LASTPIN (-3100 3200) BN 6
J 0
(-3150 3210);
DISPLAY 0.617021 (-3150 3210);
PAINT PINK (-3150 3210);
FORCEPROP 2 LAST CDS_LIB mstr_standard
J 0
(-3150 3200);
DISPLAY 0.787234 (-3150 3200);
PAINT MONO (-3150 3200);
DISPLAY INVISIBLE (-3150 3200);
FORCEPROP 1 LAST BODY_TYPE PLUMBING
J 0
(-3150 3150);
DISPLAY 1.234043 (-3150 3150);
PAINT GREEN (-3150 3150);
DISPLAY INVISIBLE (-3150 3150);
FORCEPROP 1 LAST HDL_TAP TRUE
J 0
(-2825 3075);
DISPLAY 1.234043 (-2825 3075);
PAINT GREEN (-2825 3075);
DISPLAY INVISIBLE (-2825 3075);
FORCEPROP 1 LAST PATH I159
J 0
(-3150 3200);
DISPLAY 0.936170 (-3150 3200);
PAINT GREEN (-3150 3200);
DISPLAY INVISIBLE (-3150 3200);
FORCEADD PVDDQ_DEF..1
(-1150 2475);
FORCEPROP 3 LASTPIN (-1150 2425) SIG_NAME PVDDQ_DEF\g
J 0
(-1140 2435);
DISPLAY 0.659574 (-1140 2435);
PAINT MONO (-1140 2435);
DISPLAY INVISIBLE (-1140 2435);
FORCEPROP 1 LAST VOLTAGE 1.2V
J 0
(-1195 2432);
DISPLAY 0.340426 (-1195 2432);
PAINT SKYBLUE (-1195 2432);
DISPLAY INVISIBLE (-1195 2432);
FORCEPROP 2 LAST BOM_COST MEM
J 0
(-1150 2480);
PAINT ORANGE (-1150 2480);
DISPLAY INVISIBLE (-1150 2480);
FORCEPROP 2 LAST CDS_LIB mstr_symbols
J 0
(-1150 2475);
PAINT ORANGE (-1150 2475);
DISPLAY INVISIBLE (-1150 2475);
FORCEPROP 1 LAST BODY_TYPE PLUMBING
J 0
(-1195 2432);
DISPLAY 0.340426 (-1195 2432);
PAINT GREEN (-1195 2432);
DISPLAY INVISIBLE (-1195 2432);
FORCEPROP 1 LAST PATH I16
J 0
(-1100 2500);
DISPLAY 0.872340 (-1100 2500);
PAINT AQUA (-1100 2500);
DISPLAY INVISIBLE (-1100 2500);
FORCEPROP 2 LAST ROOM DDR4_CH_C
J 0
(-1150 2575);
DISPLAY 0.787234 (-1150 2575);
PAINT ORANGE (-1150 2575);
DISPLAY INVISIBLE (-1150 2575);
FORCEPROP 1 LAST HDL_POWER PVDDQ_DEF
J 1
(-1150 2525);
DISPLAY 0.872340 (-1150 2525);
PAINT GREEN (-1150 2525);
DISPLAY INVISIBLE (-1150 2525);
FORCEADD TAP..6
(-3150 3150);
FORCEPROP 3 LASTPIN (-3100 3150) SIG_NAME M_F_CS_N<5>
J 0
(-3090 3160);
DISPLAY 0.659574 (-3090 3160);
PAINT MONO (-3090 3160);
DISPLAY INVISIBLE (-3090 3160);
FORCEPROP 1 LASTPIN (-3100 3150) BN 5
J 0
(-3150 3160);
DISPLAY 0.617021 (-3150 3160);
PAINT PINK (-3150 3160);
FORCEPROP 2 LAST CDS_LIB mstr_standard
J 0
(-3150 3150);
DISPLAY 0.787234 (-3150 3150);
PAINT MONO (-3150 3150);
DISPLAY INVISIBLE (-3150 3150);
FORCEPROP 1 LAST BODY_TYPE PLUMBING
J 0
(-3150 3100);
DISPLAY 1.234043 (-3150 3100);
PAINT GREEN (-3150 3100);
DISPLAY INVISIBLE (-3150 3100);
FORCEPROP 1 LAST HDL_TAP TRUE
J 0
(-2825 3025);
DISPLAY 1.234043 (-2825 3025);
PAINT GREEN (-2825 3025);
DISPLAY INVISIBLE (-2825 3025);
FORCEPROP 1 LAST PATH I160
J 0
(-3150 3150);
DISPLAY 0.936170 (-3150 3150);
PAINT GREEN (-3150 3150);
DISPLAY INVISIBLE (-3150 3150);
FORCEADD TAP..6
(-3150 3100);
FORCEPROP 3 LASTPIN (-3100 3100) SIG_NAME M_F_CS_N<4>
J 0
(-3090 3110);
DISPLAY 0.659574 (-3090 3110);
PAINT MONO (-3090 3110);
DISPLAY INVISIBLE (-3090 3110);
FORCEPROP 1 LASTPIN (-3100 3100) BN 4
J 0
(-3150 3110);
DISPLAY 0.617021 (-3150 3110);
PAINT PINK (-3150 3110);
FORCEPROP 2 LAST CDS_LIB mstr_standard
J 0
(-3150 3100);
DISPLAY 0.787234 (-3150 3100);
PAINT MONO (-3150 3100);
DISPLAY INVISIBLE (-3150 3100);
FORCEPROP 1 LAST BODY_TYPE PLUMBING
J 0
(-3150 3050);
DISPLAY 1.234043 (-3150 3050);
PAINT GREEN (-3150 3050);
DISPLAY INVISIBLE (-3150 3050);
FORCEPROP 1 LAST HDL_TAP TRUE
J 0
(-2825 2975);
DISPLAY 1.234043 (-2825 2975);
PAINT GREEN (-2825 2975);
DISPLAY INVISIBLE (-2825 2975);
FORCEPROP 1 LAST PATH I161
J 0
(-3150 3100);
DISPLAY 0.936170 (-3150 3100);
PAINT GREEN (-3150 3100);
DISPLAY INVISIBLE (-3150 3100);
FORCEADD OFFPAGE..1
(-3800 3300);
FORCEPROP 2 LAST $XR0 28 
J 0
(-4051 3300);
DISPLAY 0.638298 (-4051 3300);
PAINT MONO (-4051 3300);
FORCEPROP 2 LAST $XR1 53 
J 0
(-4141 3300);
DISPLAY 0.638298 (-4141 3300);
PAINT MONO (-4141 3300);
FORCEPROP 2 LAST CDS_LIB mstr_standard
J 0
(-3800 3300);
DISPLAY 0.787234 (-3800 3300);
PAINT MONO (-3800 3300);
DISPLAY INVISIBLE (-3800 3300);
FORCEPROP 1 LAST OFFPAGE TRUE
J 0
(-3475 3175);
DISPLAY 0.936170 (-3475 3175);
PAINT GREEN (-3475 3175);
DISPLAY INVISIBLE (-3475 3175);
FORCEPROP 1 LAST COMMENT_BODY TRUE
J 0
(-3675 3200);
DISPLAY 0.936170 (-3675 3200);
PAINT GREEN (-3675 3200);
DISPLAY INVISIBLE (-3675 3200);
FORCEPROP 2 LAST PATH I163
J 0
(-3750 3375);
DISPLAY 0.787234 (-3750 3375);
PAINT MONO (-3750 3375);
DISPLAY INVISIBLE (-3750 3375);
FORCEADD OFFPAGE..1
(-3800 3050);
FORCEPROP 2 LAST $XR0 28 
J 0
(-4051 3050);
DISPLAY 0.638298 (-4051 3050);
PAINT MONO (-4051 3050);
FORCEPROP 2 LAST $XR1 53 
J 0
(-4141 3050);
DISPLAY 0.638298 (-4141 3050);
PAINT MONO (-4141 3050);
FORCEPROP 2 LAST CDS_LIB mstr_standard
J 0
(-3800 3050);
DISPLAY 0.787234 (-3800 3050);
PAINT MONO (-3800 3050);
DISPLAY INVISIBLE (-3800 3050);
FORCEPROP 1 LAST OFFPAGE TRUE
J 0
(-3475 2925);
DISPLAY 0.936170 (-3475 2925);
PAINT GREEN (-3475 2925);
DISPLAY INVISIBLE (-3475 2925);
FORCEPROP 1 LAST COMMENT_BODY TRUE
J 0
(-3675 2950);
DISPLAY 0.936170 (-3675 2950);
PAINT GREEN (-3675 2950);
DISPLAY INVISIBLE (-3675 2950);
FORCEPROP 2 LAST PATH I164
J 0
(-3750 3125);
DISPLAY 0.787234 (-3750 3125);
PAINT MONO (-3750 3125);
DISPLAY INVISIBLE (-3750 3125);
FORCEADD TAP..6
(-3150 3000);
FORCEPROP 3 LASTPIN (-3100 3000) SIG_NAME M_F_CKE<3>
J 0
(-3090 3010);
DISPLAY 0.659574 (-3090 3010);
PAINT MONO (-3090 3010);
DISPLAY INVISIBLE (-3090 3010);
FORCEPROP 1 LASTPIN (-3100 3000) BN 3
J 0
(-3150 3010);
DISPLAY 0.617021 (-3150 3010);
PAINT PINK (-3150 3010);
FORCEPROP 2 LAST CDS_LIB mstr_standard
J 0
(-3150 3000);
DISPLAY 0.787234 (-3150 3000);
PAINT MONO (-3150 3000);
DISPLAY INVISIBLE (-3150 3000);
FORCEPROP 1 LAST BODY_TYPE PLUMBING
J 0
(-3150 2950);
DISPLAY 1.234043 (-3150 2950);
PAINT GREEN (-3150 2950);
DISPLAY INVISIBLE (-3150 2950);
FORCEPROP 1 LAST HDL_TAP TRUE
J 0
(-2825 2875);
DISPLAY 1.234043 (-2825 2875);
PAINT GREEN (-2825 2875);
DISPLAY INVISIBLE (-2825 2875);
FORCEPROP 1 LAST PATH I165
J 0
(-3150 3000);
DISPLAY 0.936170 (-3150 3000);
PAINT GREEN (-3150 3000);
DISPLAY INVISIBLE (-3150 3000);
FORCEADD TAP..6
(-3150 2950);
FORCEPROP 3 LASTPIN (-3100 2950) SIG_NAME M_F_CKE<2>
J 0
(-3090 2960);
DISPLAY 0.659574 (-3090 2960);
PAINT MONO (-3090 2960);
DISPLAY INVISIBLE (-3090 2960);
FORCEPROP 1 LASTPIN (-3100 2950) BN 2
J 0
(-3150 2960);
DISPLAY 0.617021 (-3150 2960);
PAINT PINK (-3150 2960);
FORCEPROP 2 LAST CDS_LIB mstr_standard
J 0
(-3150 2950);
DISPLAY 0.787234 (-3150 2950);
PAINT MONO (-3150 2950);
DISPLAY INVISIBLE (-3150 2950);
FORCEPROP 1 LAST BODY_TYPE PLUMBING
J 0
(-3150 2900);
DISPLAY 1.234043 (-3150 2900);
PAINT GREEN (-3150 2900);
DISPLAY INVISIBLE (-3150 2900);
FORCEPROP 1 LAST HDL_TAP TRUE
J 0
(-2825 2825);
DISPLAY 1.234043 (-2825 2825);
PAINT GREEN (-2825 2825);
DISPLAY INVISIBLE (-2825 2825);
FORCEPROP 1 LAST PATH I166
J 0
(-3150 2950);
DISPLAY 0.936170 (-3150 2950);
PAINT GREEN (-3150 2950);
DISPLAY INVISIBLE (-3150 2950);
FORCEADD TAP..6
(-3150 2850);
FORCEPROP 3 LASTPIN (-3100 2850) SIG_NAME M_F_ODT<3>
J 0
(-3090 2860);
DISPLAY 0.659574 (-3090 2860);
PAINT MONO (-3090 2860);
DISPLAY INVISIBLE (-3090 2860);
FORCEPROP 1 LASTPIN (-3100 2850) BN 3
J 0
(-3150 2860);
DISPLAY 0.617021 (-3150 2860);
PAINT PINK (-3150 2860);
FORCEPROP 2 LAST CDS_LIB mstr_standard
J 0
(-3150 2850);
DISPLAY 0.787234 (-3150 2850);
PAINT MONO (-3150 2850);
DISPLAY INVISIBLE (-3150 2850);
FORCEPROP 1 LAST BODY_TYPE PLUMBING
J 0
(-3150 2800);
DISPLAY 1.234043 (-3150 2800);
PAINT GREEN (-3150 2800);
DISPLAY INVISIBLE (-3150 2800);
FORCEPROP 1 LAST HDL_TAP TRUE
J 0
(-2825 2725);
DISPLAY 1.234043 (-2825 2725);
PAINT GREEN (-2825 2725);
DISPLAY INVISIBLE (-2825 2725);
FORCEPROP 1 LAST PATH I167
J 0
(-3150 2850);
DISPLAY 0.936170 (-3150 2850);
PAINT GREEN (-3150 2850);
DISPLAY INVISIBLE (-3150 2850);
FORCEADD TAP..6
(-3150 2800);
FORCEPROP 3 LASTPIN (-3100 2800) SIG_NAME M_F_ODT<2>
J 0
(-3090 2810);
DISPLAY 0.659574 (-3090 2810);
PAINT MONO (-3090 2810);
DISPLAY INVISIBLE (-3090 2810);
FORCEPROP 1 LASTPIN (-3100 2800) BN 2
J 0
(-3150 2810);
DISPLAY 0.617021 (-3150 2810);
PAINT PINK (-3150 2810);
FORCEPROP 2 LAST CDS_LIB mstr_standard
J 0
(-3150 2800);
DISPLAY 0.787234 (-3150 2800);
PAINT MONO (-3150 2800);
DISPLAY INVISIBLE (-3150 2800);
FORCEPROP 1 LAST BODY_TYPE PLUMBING
J 0
(-3150 2750);
DISPLAY 1.234043 (-3150 2750);
PAINT GREEN (-3150 2750);
DISPLAY INVISIBLE (-3150 2750);
FORCEPROP 1 LAST HDL_TAP TRUE
J 0
(-2825 2675);
DISPLAY 1.234043 (-2825 2675);
PAINT GREEN (-2825 2675);
DISPLAY INVISIBLE (-2825 2675);
FORCEPROP 1 LAST PATH I168
J 0
(-3150 2800);
DISPLAY 0.936170 (-3150 2800);
PAINT GREEN (-3150 2800);
DISPLAY INVISIBLE (-3150 2800);
FORCEADD OFFPAGE..1
(-3800 2900);
FORCEPROP 2 LAST $XR0 28 
J 0
(-4051 2900);
DISPLAY 0.638298 (-4051 2900);
PAINT MONO (-4051 2900);
FORCEPROP 2 LAST $XR1 53 
J 0
(-4141 2900);
DISPLAY 0.638298 (-4141 2900);
PAINT MONO (-4141 2900);
FORCEPROP 2 LAST CDS_LIB mstr_standard
J 0
(-3800 2900);
DISPLAY 0.787234 (-3800 2900);
PAINT MONO (-3800 2900);
DISPLAY INVISIBLE (-3800 2900);
FORCEPROP 1 LAST OFFPAGE TRUE
J 0
(-3475 2775);
DISPLAY 0.936170 (-3475 2775);
PAINT GREEN (-3475 2775);
DISPLAY INVISIBLE (-3475 2775);
FORCEPROP 1 LAST COMMENT_BODY TRUE
J 0
(-3675 2800);
DISPLAY 0.936170 (-3675 2800);
PAINT GREEN (-3675 2800);
DISPLAY INVISIBLE (-3675 2800);
FORCEPROP 2 LAST PATH I169
J 0
(-3750 2975);
DISPLAY 0.787234 (-3750 2975);
PAINT MONO (-3750 2975);
DISPLAY INVISIBLE (-3750 2975);
FORCEADD PVTT_DEF..1
(-900 2600);
FORCEPROP 3 LASTPIN (-900 2550) SIG_NAME PVTT_DEF\g
J 0
(-890 2560);
DISPLAY 0.659574 (-890 2560);
PAINT MONO (-890 2560);
DISPLAY INVISIBLE (-890 2560);
FORCEPROP 1 LAST VOLTAGE 0.6V
J 0
(-945 2557);
DISPLAY 0.340426 (-945 2557);
PAINT SKYBLUE (-945 2557);
DISPLAY INVISIBLE (-945 2557);
FORCEPROP 2 LAST BOM_COST MEM
J 0
(-900 2605);
PAINT ORANGE (-900 2605);
DISPLAY INVISIBLE (-900 2605);
FORCEPROP 2 LAST CDS_LIB mstr_symbols
J 0
(-900 2600);
PAINT ORANGE (-900 2600);
DISPLAY INVISIBLE (-900 2600);
FORCEPROP 1 LAST BODY_TYPE PLUMBING
J 0
(-945 2557);
DISPLAY 0.340426 (-945 2557);
PAINT GREEN (-945 2557);
DISPLAY INVISIBLE (-945 2557);
FORCEPROP 1 LAST PATH I17
J 0
(-850 2625);
DISPLAY 0.872340 (-850 2625);
PAINT AQUA (-850 2625);
DISPLAY INVISIBLE (-850 2625);
FORCEPROP 2 LAST ROOM DDR4_CH_C
J 0
(-900 2700);
DISPLAY 0.787234 (-900 2700);
PAINT ORANGE (-900 2700);
DISPLAY INVISIBLE (-900 2700);
FORCEPROP 1 LAST HDL_POWER PVTT_DEF
J 1
(-900 2650);
DISPLAY 0.872340 (-900 2650);
PAINT GREEN (-900 2650);
DISPLAY INVISIBLE (-900 2650);
FORCEADD SCONN288_H44441003..4
(-50 1900);
FORCEPROP 1 LAST LOCATION J6L1
J 0
(-500 3000);
DISPLAY 0.617021 (-500 3000);
PAINT AQUA (-500 3000);
FORCEPROP 1 LAST PART_NUMBER H44441-003
J 0
(-500 850);
DISPLAY 0.617021 (-500 850);
PAINT BLUE (-500 850);
FORCEPROP 1 LAST MATERIAL SCONN
J 0
(-500 2950);
DISPLAY 0.617021 (-500 2950);
PAINT SKYBLUE (-500 2950);
FORCEPROP 2 LASTPIN (-550 2450) $PN 77
J 2
(-560 2460);
DISPLAY 0.617021 (-560 2460);
PAINT ORANGE (-560 2460);
FORCEPROP 2 LASTPIN (-550 2400) $PN 221
J 2
(-560 2410);
DISPLAY 0.617021 (-560 2410);
PAINT ORANGE (-560 2410);
FORCEPROP 2 LASTPIN (-550 2750) $PN 142
J 2
(-560 2760);
DISPLAY 0.617021 (-560 2760);
PAINT ORANGE (-560 2760);
FORCEPROP 2 LASTPIN (-550 2700) $PN 143
J 2
(-560 2710);
DISPLAY 0.617021 (-560 2710);
PAINT ORANGE (-560 2710);
FORCEPROP 2 LASTPIN (-550 2650) $PN 288
J 2
(-560 2660);
DISPLAY 0.617021 (-560 2660);
PAINT ORANGE (-560 2660);
FORCEPROP 2 LASTPIN (-550 2600) $PN 286
J 2
(-560 2610);
DISPLAY 0.617021 (-560 2610);
PAINT ORANGE (-560 2610);
FORCEPROP 2 LASTPIN (-550 2550) $PN 287
J 2
(-560 2560);
DISPLAY 0.617021 (-560 2560);
PAINT ORANGE (-560 2560);
FORCEPROP 2 LASTPIN (-550 2300) $PN 59
J 2
(-560 2310);
DISPLAY 0.617021 (-560 2310);
PAINT ORANGE (-560 2310);
FORCEPROP 2 LASTPIN (-550 2250) $PN 61
J 2
(-560 2260);
DISPLAY 0.617021 (-560 2260);
PAINT ORANGE (-560 2260);
FORCEPROP 2 LASTPIN (-550 2200) $PN 64
J 2
(-560 2210);
DISPLAY 0.617021 (-560 2210);
PAINT ORANGE (-560 2210);
FORCEPROP 2 LASTPIN (-550 2150) $PN 67
J 2
(-560 2160);
DISPLAY 0.617021 (-560 2160);
PAINT ORANGE (-560 2160);
FORCEPROP 2 LASTPIN (-550 2100) $PN 70
J 2
(-560 2110);
DISPLAY 0.617021 (-560 2110);
PAINT ORANGE (-560 2110);
FORCEPROP 2 LASTPIN (-550 2050) $PN 73
J 2
(-560 2060);
DISPLAY 0.617021 (-560 2060);
PAINT ORANGE (-560 2060);
FORCEPROP 2 LASTPIN (-550 2000) $PN 76
J 2
(-560 2010);
DISPLAY 0.617021 (-560 2010);
PAINT ORANGE (-560 2010);
FORCEPROP 2 LASTPIN (-550 1950) $PN 80
J 2
(-560 1960);
DISPLAY 0.617021 (-560 1960);
PAINT ORANGE (-560 1960);
FORCEPROP 2 LASTPIN (-550 1900) $PN 83
J 2
(-560 1910);
DISPLAY 0.617021 (-560 1910);
PAINT ORANGE (-560 1910);
FORCEPROP 2 LASTPIN (-550 1850) $PN 85
J 2
(-560 1860);
DISPLAY 0.617021 (-560 1860);
PAINT ORANGE (-560 1860);
FORCEPROP 2 LASTPIN (-550 1800) $PN 88
J 2
(-560 1810);
DISPLAY 0.617021 (-560 1810);
PAINT ORANGE (-560 1810);
FORCEPROP 2 LASTPIN (-550 1750) $PN 90
J 2
(-560 1760);
DISPLAY 0.617021 (-560 1760);
PAINT ORANGE (-560 1760);
FORCEPROP 2 LASTPIN (-550 1700) $PN 92
J 2
(-560 1710);
DISPLAY 0.617021 (-560 1710);
PAINT ORANGE (-560 1710);
FORCEPROP 2 LASTPIN (-550 1650) $PN 204
J 2
(-560 1660);
DISPLAY 0.617021 (-560 1660);
PAINT ORANGE (-560 1660);
FORCEPROP 2 LASTPIN (-550 1600) $PN 206
J 2
(-560 1610);
DISPLAY 0.617021 (-560 1610);
PAINT ORANGE (-560 1610);
FORCEPROP 2 LASTPIN (-550 1550) $PN 209
J 2
(-560 1560);
DISPLAY 0.617021 (-560 1560);
PAINT ORANGE (-560 1560);
FORCEPROP 2 LASTPIN (-550 1500) $PN 212
J 2
(-560 1510);
DISPLAY 0.617021 (-560 1510);
PAINT ORANGE (-560 1510);
FORCEPROP 2 LASTPIN (-550 1450) $PN 215
J 2
(-560 1460);
DISPLAY 0.617021 (-560 1460);
PAINT ORANGE (-560 1460);
FORCEPROP 2 LASTPIN (-550 1400) $PN 217
J 2
(-560 1410);
DISPLAY 0.617021 (-560 1410);
PAINT ORANGE (-560 1410);
FORCEPROP 2 LASTPIN (-550 1350) $PN 220
J 2
(-560 1360);
DISPLAY 0.617021 (-560 1360);
PAINT ORANGE (-560 1360);
FORCEPROP 2 LASTPIN (-550 1300) $PN 223
J 2
(-560 1310);
DISPLAY 0.617021 (-560 1310);
PAINT ORANGE (-560 1310);
FORCEPROP 2 LASTPIN (-550 1250) $PN 226
J 2
(-560 1260);
DISPLAY 0.617021 (-560 1260);
PAINT ORANGE (-560 1260);
FORCEPROP 2 LASTPIN (-550 1200) $PN 229
J 2
(-560 1210);
DISPLAY 0.617021 (-560 1210);
PAINT ORANGE (-560 1210);
FORCEPROP 2 LASTPIN (-550 1150) $PN 231
J 2
(-560 1160);
DISPLAY 0.617021 (-560 1160);
PAINT ORANGE (-560 1160);
FORCEPROP 2 LASTPIN (-550 1100) $PN 233
J 2
(-560 1110);
DISPLAY 0.617021 (-560 1110);
PAINT ORANGE (-560 1110);
FORCEPROP 2 LASTPIN (-550 1050) $PN 236
J 2
(-560 1060);
DISPLAY 0.617021 (-560 1060);
PAINT ORANGE (-560 1060);
FORCEPROP 2 LASTPIN (450 2750) $PN 1
J 0
(460 2760);
DISPLAY 0.617021 (460 2760);
PAINT ORANGE (460 2760);
FORCEPROP 2 LASTPIN (450 2700) $PN 145
J 0
(460 2710);
DISPLAY 0.617021 (460 2710);
PAINT ORANGE (460 2710);
FORCEPROP 1 LAST PACK_TYPE PIP
J 0
(-500 3050);
PAINT SKYBLUE (-500 3050);
DISPLAY INVISIBLE (-500 3050);
FORCEPROP 2 LAST BOM_COST MEM
J 0
(-50 1900);
PAINT ORANGE (-50 1900);
DISPLAY INVISIBLE (-50 1900);
FORCEPROP 2 LAST CDS_LIB mstr_sconn
J 0
(-50 1900);
PAINT ORANGE (-50 1900);
DISPLAY INVISIBLE (-50 1900);
FORCEPROP 2 LAST SEC_TYPE PIP
J 0
(-500 3050);
DISPLAY 1.021277 (-500 3050);
PAINT ORANGE (-500 3050);
DISPLAY INVISIBLE (-500 3050);
FORCEPROP 2 LAST SEC 4
J 0
(-500 3050);
DISPLAY 0.680851 (-500 3050);
PAINT MONO (-500 3050);
DISPLAY INVISIBLE (-500 3050);
FORCEPROP 2 LAST CDS_LOCATION J6L1
J 0
(-500 3000);
DISPLAY 0.617021 (-500 3000);
PAINT AQUA (-500 3000);
DISPLAY INVISIBLE (-500 3000);
FORCEPROP 1 LAST PATH I170
J 0
(-50 2950);
PAINT GREEN (-50 2950);
DISPLAY INVISIBLE (-50 2950);
FORCEPROP 2 LAST ROOM DDR4_CH_F1
J 0
(-50 1900);
PAINT ORANGE (-50 1900);
DISPLAY INVISIBLE (-50 1900);
FORCEADD GND..1
R 2
(2500 1250);
FORCEPROP 3 LASTPIN (2500 1300) SIG_NAME GND\g
J 0
(2510 1310);
DISPLAY 0.659574 (2510 1310);
PAINT MONO (2510 1310);
DISPLAY INVISIBLE (2510 1310);
FORCEPROP 1 LAST VOLTAGE 0
J 0
(2500 1250);
PAINT SKYBLUE (2500 1250);
DISPLAY INVISIBLE (2500 1250);
FORCEPROP 1 LAST SIZE 1B
J 2
(2425 1200);
DISPLAY 1.170213 (2425 1200);
PAINT GREEN (2425 1200);
DISPLAY INVISIBLE (2425 1200);
FORCEPROP 2 LAST CDS_LIB mstr_symbols
J 0
(2500 1250);
DISPLAY 0.787234 (2500 1250);
PAINT MONO (2500 1250);
DISPLAY INVISIBLE (2500 1250);
FORCEPROP 2 LAST BOM_COST MEM
J 0
(2500 1255);
PAINT ORANGE (2500 1255);
DISPLAY INVISIBLE (2500 1255);
FORCEPROP 1 LAST BODY_TYPE PLUMBING
J 2
(2545 1207);
DISPLAY 0.340426 (2545 1207);
PAINT GREEN (2545 1207);
DISPLAY INVISIBLE (2545 1207);
FORCEPROP 1 LAST PATH I171
J 2
(2425 1250);
DISPLAY 1.404255 (2425 1250);
PAINT GREEN (2425 1250);
DISPLAY INVISIBLE (2425 1250);
FORCEPROP 2 LAST ROOM DDR4_CH_C
J 0
(2500 1255);
PAINT ORANGE (2500 1255);
DISPLAY INVISIBLE (2500 1255);
FORCEPROP 1 LAST HDL_POWER GND
J 2
(2500 1400);
DISPLAY 0.553191 (2500 1400);
PAINT GREEN (2500 1400);
DISPLAY INVISIBLE (2500 1400);
FORCEADD OFFPAGE..1
(-3800 1700);
FORCEPROP 2 LAST $XR0 99 
J 0
(-4051 1700);
DISPLAY 0.638298 (-4051 1700);
PAINT MONO (-4051 1700);
FORCEPROP 2 LAST $XR1 49 
J 0
(-4141 1700);
DISPLAY 0.638298 (-4141 1700);
PAINT MONO (-4141 1700);
FORCEPROP 2 LAST $XR2 50 
J 0
(-4231 1700);
DISPLAY 0.638298 (-4231 1700);
PAINT MONO (-4231 1700);
FORCEPROP 2 LAST $XR3 51 
J 0
(-4321 1700);
DISPLAY 0.638298 (-4321 1700);
PAINT MONO (-4321 1700);
FORCEPROP 2 LAST $XR4 52 
J 0
(-4411 1700);
DISPLAY 0.638298 (-4411 1700);
PAINT MONO (-4411 1700);
FORCEPROP 2 LAST $XR5 53 
J 0
(-4501 1700);
DISPLAY 0.638298 (-4501 1700);
PAINT MONO (-4501 1700);
FORCEPROP 2 LAST CDS_LIB mstr_standard
J 0
(-3800 1700);
DISPLAY 0.787234 (-3800 1700);
PAINT MONO (-3800 1700);
DISPLAY INVISIBLE (-3800 1700);
FORCEPROP 1 LAST OFFPAGE TRUE
J 0
(-3475 1575);
DISPLAY 0.936170 (-3475 1575);
PAINT GREEN (-3475 1575);
DISPLAY INVISIBLE (-3475 1575);
FORCEPROP 1 LAST COMMENT_BODY TRUE
J 0
(-3675 1600);
DISPLAY 0.936170 (-3675 1600);
PAINT GREEN (-3675 1600);
DISPLAY INVISIBLE (-3675 1600);
FORCEPROP 2 LAST PATH I172
J 0
(-4075 1750);
DISPLAY 0.787234 (-4075 1750);
PAINT ORANGE (-4075 1750);
DISPLAY INVISIBLE (-4075 1750);
FORCEADD OFFPAGE..6
(-3800 1750);
FORCEPROP 2 LAST $XR0 49 
J 0
(-4049 1750);
DISPLAY 0.638298 (-4049 1750);
PAINT MONO (-4049 1750);
FORCEPROP 2 LAST $XR1 50 
J 0
(-4139 1750);
DISPLAY 0.638298 (-4139 1750);
PAINT MONO (-4139 1750);
FORCEPROP 2 LAST $XR2 51 
J 0
(-4229 1750);
DISPLAY 0.638298 (-4229 1750);
PAINT MONO (-4229 1750);
FORCEPROP 2 LAST $XR3 52 
J 0
(-4319 1750);
DISPLAY 0.638298 (-4319 1750);
PAINT MONO (-4319 1750);
FORCEPROP 2 LAST $XR4 53 
J 0
(-4409 1750);
DISPLAY 0.638298 (-4409 1750);
PAINT MONO (-4409 1750);
FORCEPROP 2 LAST $XR5 99 
J 0
(-4499 1750);
DISPLAY 0.638298 (-4499 1750);
PAINT MONO (-4499 1750);
FORCEPROP 2 LAST CDS_LIB mstr_standard
J 0
(-3800 1750);
DISPLAY 0.787234 (-3800 1750);
PAINT MONO (-3800 1750);
DISPLAY INVISIBLE (-3800 1750);
FORCEPROP 1 LAST OFFPAGE TRUE
J 0
(-3475 1625);
DISPLAY 0.936170 (-3475 1625);
PAINT GREEN (-3475 1625);
DISPLAY INVISIBLE (-3475 1625);
FORCEPROP 1 LAST COMMENT_BODY TRUE
J 0
(-3700 1675);
DISPLAY 0.936170 (-3700 1675);
PAINT GREEN (-3700 1675);
DISPLAY INVISIBLE (-3700 1675);
FORCEPROP 2 LAST PATH I173
J 0
(-4125 1800);
DISPLAY 0.787234 (-4125 1800);
PAINT ORANGE (-4125 1800);
DISPLAY INVISIBLE (-4125 1800);
FORCEADD OFFPAGE..1
(-4750 1600);
FORCEPROP 2 LAST $XR0 98 
J 0
(-4971 1600);
DISPLAY 0.638298 (-4971 1600);
PAINT MONO (-4971 1600);
FORCEPROP 2 LAST $XR1 53 
J 0
(-5061 1600);
DISPLAY 0.638298 (-5061 1600);
PAINT MONO (-5061 1600);
FORCEPROP 2 LAST CDS_LIB mstr_standard
J 0
(-4750 1600);
DISPLAY 0.787234 (-4750 1600);
PAINT MONO (-4750 1600);
DISPLAY INVISIBLE (-4750 1600);
FORCEPROP 1 LAST OFFPAGE TRUE
J 0
(-4425 1475);
DISPLAY 0.936170 (-4425 1475);
PAINT GREEN (-4425 1475);
DISPLAY INVISIBLE (-4425 1475);
FORCEPROP 1 LAST COMMENT_BODY TRUE
J 0
(-4625 1500);
DISPLAY 0.936170 (-4625 1500);
PAINT GREEN (-4625 1500);
DISPLAY INVISIBLE (-4625 1500);
FORCEPROP 2 LAST PATH I174
J 0
(-5000 1650);
DISPLAY 0.787234 (-5000 1650);
PAINT ORANGE (-5000 1650);
DISPLAY INVISIBLE (-5000 1650);
FORCEADD OFFPAGE..5
(-4125 2400);
FORCEPROP 2 LAST $XR0 43 
J 0
(-4379 2400);
DISPLAY 0.638298 (-4379 2400);
PAINT MONO (-4379 2400);
FORCEPROP 2 LAST $XR1 44 
J 0
(-4469 2400);
DISPLAY 0.638298 (-4469 2400);
PAINT MONO (-4469 2400);
FORCEPROP 2 LAST $XR2 45 
J 0
(-4559 2400);
DISPLAY 0.638298 (-4559 2400);
PAINT MONO (-4559 2400);
FORCEPROP 2 LAST $XR3 46 
J 0
(-4649 2400);
DISPLAY 0.638298 (-4649 2400);
PAINT MONO (-4649 2400);
FORCEPROP 2 LAST $XR4 47 
J 0
(-4739 2400);
DISPLAY 0.638298 (-4739 2400);
PAINT MONO (-4739 2400);
FORCEPROP 2 LAST $XR5 48 
J 0
(-4829 2400);
DISPLAY 0.638298 (-4829 2400);
PAINT MONO (-4829 2400);
FORCEPROP 2 LAST $XR6 49 
J 0
(-4919 2400);
DISPLAY 0.638298 (-4919 2400);
PAINT MONO (-4919 2400);
FORCEPROP 2 LAST $XR7 50 
J 0
(-5009 2400);
DISPLAY 0.638298 (-5009 2400);
PAINT MONO (-5009 2400);
FORCEPROP 2 LAST $XR8 51 
J 0
(-5099 2400);
DISPLAY 0.638298 (-5099 2400);
PAINT MONO (-5099 2400);
FORCEPROP 2 LAST $XR9 52 
J 0
(-5189 2400);
DISPLAY 0.638298 (-5189 2400);
PAINT MONO (-5189 2400);
FORCEPROP 2 LAST $XR10 53 
J 0
(-4379 2364);
DISPLAY 0.638298 (-4379 2364);
PAINT MONO (-4379 2364);
FORCEPROP 2 LAST $XR11 77 
J 0
(-4469 2364);
DISPLAY 0.638298 (-4469 2364);
PAINT MONO (-4469 2364);
FORCEPROP 2 LAST $XR12 78 
J 0
(-4559 2364);
DISPLAY 0.638298 (-4559 2364);
PAINT MONO (-4559 2364);
FORCEPROP 2 LAST $XR13 79 
J 0
(-4649 2364);
DISPLAY 0.638298 (-4649 2364);
PAINT MONO (-4649 2364);
FORCEPROP 2 LAST $XR14 80 
J 0
(-4739 2364);
DISPLAY 0.638298 (-4739 2364);
PAINT MONO (-4739 2364);
FORCEPROP 2 LAST $XR15 81 
J 0
(-4829 2364);
DISPLAY 0.638298 (-4829 2364);
PAINT MONO (-4829 2364);
FORCEPROP 2 LAST $XR16 82 
J 0
(-4919 2364);
DISPLAY 0.638298 (-4919 2364);
PAINT MONO (-4919 2364);
FORCEPROP 2 LAST $XR17 83 
J 0
(-5009 2364);
DISPLAY 0.638298 (-5009 2364);
PAINT MONO (-5009 2364);
FORCEPROP 2 LAST $XR18 84 
J 0
(-5099 2364);
DISPLAY 0.638298 (-5099 2364);
PAINT MONO (-5099 2364);
FORCEPROP 2 LAST $XR19 85 
J 0
(-4379 2436);
DISPLAY 0.638298 (-4379 2436);
PAINT MONO (-4379 2436);
FORCEPROP 2 LAST $XR20 86 
J 0
(-4469 2436);
DISPLAY 0.638298 (-4469 2436);
PAINT MONO (-4469 2436);
FORCEPROP 2 LAST $XR21 87 
J 0
(-4559 2436);
DISPLAY 0.638298 (-4559 2436);
PAINT MONO (-4559 2436);
FORCEPROP 2 LAST $XR22 88 
J 0
(-4649 2436);
DISPLAY 0.638298 (-4649 2436);
PAINT MONO (-4649 2436);
FORCEPROP 2 LAST $XR23 94 
J 0
(-4739 2436);
DISPLAY 0.638298 (-4739 2436);
PAINT MONO (-4739 2436);
FORCEPROP 2 LAST CDS_LIB mstr_standard
J 0
(-4125 2400);
DISPLAY 0.787234 (-4125 2400);
PAINT MONO (-4125 2400);
DISPLAY INVISIBLE (-4125 2400);
FORCEPROP 1 LAST OFFPAGE TRUE
J 0
(-3800 2275);
DISPLAY 1.404255 (-3800 2275);
PAINT GREEN (-3800 2275);
DISPLAY INVISIBLE (-3800 2275);
FORCEPROP 1 LAST COMMENT_BODY TRUE
J 0
(-4025 2325);
DISPLAY 1.404255 (-4025 2325);
PAINT GREEN (-4025 2325);
DISPLAY INVISIBLE (-4025 2325);
FORCEPROP 2 LAST PATH I175
J 0
(-4075 2475);
DISPLAY 0.787234 (-4075 2475);
PAINT ORANGE (-4075 2475);
DISPLAY INVISIBLE (-4075 2475);
FORCEADD GND..1
(-4600 1150);
FORCEPROP 3 LASTPIN (-4600 1200) SIG_NAME GND\g
J 0
(-4590 1210);
DISPLAY 0.659574 (-4590 1210);
PAINT MONO (-4590 1210);
DISPLAY INVISIBLE (-4590 1210);
FORCEPROP 1 LAST VOLTAGE 0
J 0
(-4600 1150);
PAINT SKYBLUE (-4600 1150);
DISPLAY INVISIBLE (-4600 1150);
FORCEPROP 2 LAST CDS_LIB mstr_symbols
J 0
(-4600 1150);
PAINT ORANGE (-4600 1150);
DISPLAY INVISIBLE (-4600 1150);
FORCEPROP 2 LAST BOM_COST MEM
J 0
(-4600 1155);
PAINT ORANGE (-4600 1155);
DISPLAY INVISIBLE (-4600 1155);
FORCEPROP 1 LAST SIZE 1B
J 0
(-4525 1100);
DISPLAY 1.787234 (-4525 1100);
PAINT GREEN (-4525 1100);
DISPLAY INVISIBLE (-4525 1100);
FORCEPROP 1 LAST BODY_TYPE PLUMBING
J 0
(-4645 1107);
DISPLAY 0.340426 (-4645 1107);
PAINT GREEN (-4645 1107);
DISPLAY INVISIBLE (-4645 1107);
FORCEPROP 1 LAST PATH I178
J 0
(-4525 1150);
DISPLAY 1.404255 (-4525 1150);
PAINT GREEN (-4525 1150);
DISPLAY INVISIBLE (-4525 1150);
FORCEPROP 2 LAST ROOM DDR4_CH_C
J 0
(-4600 1155);
PAINT ORANGE (-4600 1155);
DISPLAY INVISIBLE (-4600 1155);
FORCEPROP 1 LAST HDL_POWER GND
J 0
(-4600 1300);
DISPLAY 1.404255 (-4600 1300);
PAINT GREEN (-4600 1300);
DISPLAY INVISIBLE (-4600 1300);
FORCEADD CAP_A..1
R 2
(-4600 1400);
FORCEPROP 1 LAST LOCATION C4A5
J 2
(-4650 1500);
DISPLAY 0.617021 (-4650 1500);
PAINT AQUA (-4650 1500);
FORCEPROP 1 LAST PART_NUMBER A36096-045
J 2
(-4650 1250);
DISPLAY 0.617021 (-4650 1250);
PAINT BLUE (-4650 1250);
FORCEPROP 1 LAST VALUE 0.01UF
J 2
(-4650 1450);
DISPLAY 0.617021 (-4650 1450);
PAINT SKYBLUE (-4650 1450);
FORCEPROP 1 LAST TOLERANCE 10%
J 2
(-4650 1350);
DISPLAY 0.617021 (-4650 1350);
PAINT SKYBLUE (-4650 1350);
FORCEPROP 1 LAST PACK_TYPE 0402V
J 2
(-4650 1200);
DISPLAY 0.617021 (-4650 1200);
PAINT SKYBLUE (-4650 1200);
FORCEPROP 1 LAST VOLTAGE 25V
J 2
(-4650 1400);
DISPLAY 0.617021 (-4650 1400);
PAINT SKYBLUE (-4650 1400);
FORCEPROP 1 LAST MATERIAL X7R
J 2
(-4650 1300);
DISPLAY 0.617021 (-4650 1300);
PAINT SKYBLUE (-4650 1300);
FORCEPROP 2 LAST CDS_LOCATION C4A5
J 2
(-4650 1500);
DISPLAY 0.617021 (-4650 1500);
PAINT AQUA (-4650 1500);
DISPLAY INVISIBLE (-4650 1500);
FORCEPROP 2 LAST BOM_COST MEM
J 0
(-4600 1400);
PAINT ORANGE (-4600 1400);
DISPLAY INVISIBLE (-4600 1400);
FORCEPROP 2 LAST CDS_LIB dev_discrete
J 0
(-4600 1400);
PAINT ORANGE (-4600 1400);
DISPLAY INVISIBLE (-4600 1400);
FORCEPROP 2 LAST CDS_SEC 1
J 2
(-4650 1600);
PAINT MONO (-4650 1600);
DISPLAY INVISIBLE (-4650 1600);
FORCEPROP 2 LAST $SEC 1
J 0
(-4650 1600);
PAINT MONO (-4650 1600);
DISPLAY INVISIBLE (-4650 1600);
FORCEPROP 1 LAST PATH I179
J 2
(-4650 1550);
DISPLAY 0.978723 (-4650 1550);
PAINT WHITE (-4650 1550);
DISPLAY INVISIBLE (-4650 1550);
FORCEPROP 2 LAST ROOM DDR4_CH_F1
J 0
(-4600 1400);
PAINT ORANGE (-4600 1400);
DISPLAY INVISIBLE (-4600 1400);
FORCEPROP 1 LASTPIN (-4600 1500) $PN 1
J 2
(-4610 1480);
DISPLAY 0.787234 (-4610 1480);
PAINT ORANGE (-4610 1480);
DISPLAY INVISIBLE (-4610 1480);
FORCEPROP 1 LASTPIN (-4600 1300) $PN 2
J 2
(-4610 1280);
DISPLAY 0.787234 (-4610 1280);
PAINT ORANGE (-4610 1280);
DISPLAY INVISIBLE (-4610 1280);
FORCEADD PVPP_DEF..1
(-750 2900);
FORCEPROP 3 LASTPIN (-750 2850) SIG_NAME PVPP_DEF\g
J 0
(-740 2860);
DISPLAY 0.659574 (-740 2860);
PAINT MONO (-740 2860);
DISPLAY INVISIBLE (-740 2860);
FORCEPROP 1 LAST VOLTAGE 2.5V
J 0
(-795 2857);
DISPLAY 0.340426 (-795 2857);
PAINT SKYBLUE (-795 2857);
DISPLAY INVISIBLE (-795 2857);
FORCEPROP 0 LAST BOM_COST MEM
J 0
(-750 3000);
PAINT ORANGE (-750 3000);
DISPLAY INVISIBLE (-750 3000);
FORCEPROP 2 LAST CDS_LIB mstr_symbols
J 0
(-750 2900);
PAINT ORANGE (-750 2900);
DISPLAY INVISIBLE (-750 2900);
FORCEPROP 1 LAST BODY_TYPE PLUMBING
J 0
(-795 2857);
DISPLAY 0.340426 (-795 2857);
PAINT GREEN (-795 2857);
DISPLAY INVISIBLE (-795 2857);
FORCEPROP 1 LAST PATH I180
J 0
(-700 2925);
DISPLAY 0.872340 (-700 2925);
PAINT AQUA (-700 2925);
DISPLAY INVISIBLE (-700 2925);
FORCEPROP 2 LAST ROOM DDR4_CH_C
J 0
(-750 3000);
PAINT ORANGE (-750 3000);
DISPLAY INVISIBLE (-750 3000);
FORCEPROP 1 LAST HDL_POWER PVPP_DEF
J 1
(-750 2950);
DISPLAY 0.872340 (-750 2950);
PAINT GREEN (-750 2950);
DISPLAY INVISIBLE (-750 2950);
FORCEADD PVPP_DEF..1
(-5200 2100);
FORCEPROP 3 LASTPIN (-5200 2050) SIG_NAME PVPP_DEF\g
J 0
(-5190 2060);
DISPLAY 0.659574 (-5190 2060);
PAINT MONO (-5190 2060);
DISPLAY INVISIBLE (-5190 2060);
FORCEPROP 1 LAST VOLTAGE 2.5V
J 0
(-5245 2057);
DISPLAY 0.340426 (-5245 2057);
PAINT SKYBLUE (-5245 2057);
DISPLAY INVISIBLE (-5245 2057);
FORCEPROP 0 LAST BOM_COST MEM
J 0
(-5200 2200);
PAINT ORANGE (-5200 2200);
DISPLAY INVISIBLE (-5200 2200);
FORCEPROP 2 LAST CDS_LIB mstr_symbols
J 0
(-5200 2100);
PAINT ORANGE (-5200 2100);
DISPLAY INVISIBLE (-5200 2100);
FORCEPROP 1 LAST BODY_TYPE PLUMBING
J 0
(-5245 2057);
DISPLAY 0.340426 (-5245 2057);
PAINT GREEN (-5245 2057);
DISPLAY INVISIBLE (-5245 2057);
FORCEPROP 1 LAST PATH I181
J 0
(-5150 2125);
DISPLAY 0.872340 (-5150 2125);
PAINT AQUA (-5150 2125);
DISPLAY INVISIBLE (-5150 2125);
FORCEPROP 2 LAST ROOM DDR4_CH_C
J 0
(-5200 2200);
PAINT ORANGE (-5200 2200);
DISPLAY INVISIBLE (-5200 2200);
FORCEPROP 1 LAST HDL_POWER PVPP_DEF
J 1
(-5200 2150);
DISPLAY 0.872340 (-5200 2150);
PAINT GREEN (-5200 2150);
DISPLAY INVISIBLE (-5200 2150);
FORCEADD OFFPAGE..1
(-3800 1300);
FORCEPROP 2 LAST $XR0 89 
J 0
(-4051 1300);
DISPLAY 0.638298 (-4051 1300);
PAINT MONO (-4051 1300);
FORCEPROP 2 LAST $XR1 49 
J 0
(-4141 1300);
DISPLAY 0.638298 (-4141 1300);
PAINT MONO (-4141 1300);
FORCEPROP 2 LAST $XR2 50 
J 0
(-4231 1300);
DISPLAY 0.638298 (-4231 1300);
PAINT MONO (-4231 1300);
FORCEPROP 2 LAST $XR3 51 
J 0
(-4321 1300);
DISPLAY 0.638298 (-4321 1300);
PAINT MONO (-4321 1300);
FORCEPROP 2 LAST $XR4 52 
J 0
(-4411 1300);
DISPLAY 0.638298 (-4411 1300);
PAINT MONO (-4411 1300);
FORCEPROP 2 LAST $XR5 53 
J 0
(-4501 1300);
DISPLAY 0.638298 (-4501 1300);
PAINT MONO (-4501 1300);
FORCEPROP 2 LAST CDS_LIB mstr_standard
J 0
(-3800 1300);
PAINT ORANGE (-3800 1300);
DISPLAY INVISIBLE (-3800 1300);
FORCEPROP 1 LAST OFFPAGE TRUE
J 0
(-3475 1175);
DISPLAY 0.936170 (-3475 1175);
PAINT GREEN (-3475 1175);
DISPLAY INVISIBLE (-3475 1175);
FORCEPROP 1 LAST COMMENT_BODY TRUE
J 0
(-3675 1200);
DISPLAY 0.936170 (-3675 1200);
PAINT GREEN (-3675 1200);
DISPLAY INVISIBLE (-3675 1200);
FORCEPROP 2 LAST PATH I182
J 0
(-3750 1375);
PAINT ORANGE (-3750 1375);
DISPLAY INVISIBLE (-3750 1375);
FORCEADD GND..1
(-5200 1750);
FORCEPROP 3 LASTPIN (-5200 1800) SIG_NAME GND\g
J 0
(-5190 1810);
DISPLAY 0.659574 (-5190 1810);
PAINT MONO (-5190 1810);
DISPLAY INVISIBLE (-5190 1810);
FORCEPROP 1 LAST VOLTAGE 0
J 0
(-5200 1750);
PAINT SKYBLUE (-5200 1750);
DISPLAY INVISIBLE (-5200 1750);
FORCEPROP 1 LAST SIZE 1B
J 0
(-5125 1700);
DISPLAY 1.787234 (-5125 1700);
PAINT GREEN (-5125 1700);
DISPLAY INVISIBLE (-5125 1700);
FORCEPROP 2 LAST BOM_COST MEM
J 0
(-5200 1755);
PAINT ORANGE (-5200 1755);
DISPLAY INVISIBLE (-5200 1755);
FORCEPROP 2 LAST CDS_LIB mstr_symbols
J 0
(-5200 1750);
PAINT ORANGE (-5200 1750);
DISPLAY INVISIBLE (-5200 1750);
FORCEPROP 1 LAST BODY_TYPE PLUMBING
J 0
(-5245 1707);
DISPLAY 0.340426 (-5245 1707);
PAINT GREEN (-5245 1707);
DISPLAY INVISIBLE (-5245 1707);
FORCEPROP 1 LAST PATH I186
J 0
(-5125 1750);
DISPLAY 0.872340 (-5125 1750);
PAINT AQUA (-5125 1750);
DISPLAY INVISIBLE (-5125 1750);
FORCEPROP 2 LAST ROOM DDR4_CH_C
J 0
(-5200 1755);
PAINT ORANGE (-5200 1755);
DISPLAY INVISIBLE (-5200 1755);
FORCEPROP 1 LAST HDL_POWER GND
J 0
(-5200 1900);
DISPLAY 1.404255 (-5200 1900);
PAINT GREEN (-5200 1900);
DISPLAY INVISIBLE (-5200 1900);
FORCEADD P12V_NVDIMM_DEF..1
(650 2975);
FORCEPROP 3 LASTPIN (650 2925) SIG_NAME P12V_NVDIMM_DEF\g
J 0
(660 2935);
DISPLAY 0.659574 (660 2935);
PAINT MONO (660 2935);
DISPLAY INVISIBLE (660 2935);
FORCEPROP 1 LAST VOLTAGE 12.0
J 0
(605 2932);
DISPLAY 0.340426 (605 2932);
PAINT SKYBLUE (605 2932);
DISPLAY INVISIBLE (605 2932);
FORCEPROP 2 LAST CDS_LIB mstr_symbols
J 0
(650 2975);
PAINT ORANGE (650 2975);
DISPLAY INVISIBLE (650 2975);
FORCEPROP 1 LAST BODY_TYPE PLUMBING
J 0
(605 2932);
DISPLAY 0.340426 (605 2932);
PAINT GREEN (605 2932);
DISPLAY INVISIBLE (605 2932);
FORCEPROP 1 LAST PATH I187
J 0
(700 3000);
DISPLAY 0.872340 (700 3000);
PAINT AQUA (700 3000);
DISPLAY INVISIBLE (700 3000);
FORCEPROP 1 LAST HDL_POWER P12V_NVDIMM_DEF
J 1
(650 3025);
DISPLAY 0.872340 (650 3025);
PAINT GREEN (650 3025);
DISPLAY INVISIBLE (650 3025);
FORCEADD TAP..6
R 2
(900 4500);
FORCEPROP 3 LASTPIN (850 4500) SIG_NAME M_F_DQS_DN<11>
J 0
(860 4510);
DISPLAY 0.659574 (860 4510);
PAINT MONO (860 4510);
DISPLAY INVISIBLE (860 4510);
FORCEPROP 1 LASTPIN (850 4500) BN 11
J 2
(900 4510);
DISPLAY 0.617021 (900 4510);
PAINT PINK (900 4510);
FORCEPROP 2 LAST CDS_LIB mstr_standard
J 0
(900 4500);
DISPLAY 0.787234 (900 4500);
PAINT MONO (900 4500);
DISPLAY INVISIBLE (900 4500);
FORCEPROP 1 LAST BODY_TYPE PLUMBING
J 2
(900 4450);
DISPLAY 1.234043 (900 4450);
PAINT GREEN (900 4450);
DISPLAY INVISIBLE (900 4450);
FORCEPROP 1 LAST HDL_TAP TRUE
J 2
(575 4375);
DISPLAY 1.234043 (575 4375);
PAINT GREEN (575 4375);
DISPLAY INVISIBLE (575 4375);
FORCEPROP 1 LAST PATH I19
J 2
(900 4500);
DISPLAY 0.936170 (900 4500);
PAINT GREEN (900 4500);
DISPLAY INVISIBLE (900 4500);
FORCEADD OFFPAGE..3
(1575 5150);
FORCEPROP 2 LAST $XR0 28 
J 0
(1789 5150);
DISPLAY 0.638298 (1789 5150);
PAINT MONO (1789 5150);
FORCEPROP 2 LAST $XR1 53 
J 0
(1879 5150);
DISPLAY 0.638298 (1879 5150);
PAINT MONO (1879 5150);
FORCEPROP 2 LAST CDS_LIB mstr_standard
J 0
(1575 5150);
DISPLAY 0.787234 (1575 5150);
PAINT MONO (1575 5150);
DISPLAY INVISIBLE (1575 5150);
FORCEPROP 1 LAST OFFPAGE TRUE
J 0
(1900 5025);
DISPLAY 0.936170 (1900 5025);
PAINT GREEN (1900 5025);
DISPLAY INVISIBLE (1900 5025);
FORCEPROP 1 LAST COMMENT_BODY TRUE
J 0
(1525 5050);
DISPLAY 0.936170 (1525 5050);
PAINT GREEN (1525 5050);
DISPLAY INVISIBLE (1525 5050);
FORCEPROP 2 LAST PATH I2
J 0
(1775 5225);
DISPLAY 0.787234 (1775 5225);
PAINT MONO (1775 5225);
DISPLAY INVISIBLE (1775 5225);
FORCEADD TAP..6
R 2
(900 4400);
FORCEPROP 3 LASTPIN (850 4400) SIG_NAME M_F_DQS_DN<10>
J 0
(860 4410);
DISPLAY 0.659574 (860 4410);
PAINT MONO (860 4410);
DISPLAY INVISIBLE (860 4410);
FORCEPROP 1 LASTPIN (850 4400) BN 10
J 2
(900 4410);
DISPLAY 0.617021 (900 4410);
PAINT PINK (900 4410);
FORCEPROP 2 LAST CDS_LIB mstr_standard
J 0
(900 4400);
DISPLAY 0.787234 (900 4400);
PAINT MONO (900 4400);
DISPLAY INVISIBLE (900 4400);
FORCEPROP 1 LAST BODY_TYPE PLUMBING
J 2
(900 4350);
DISPLAY 1.234043 (900 4350);
PAINT GREEN (900 4350);
DISPLAY INVISIBLE (900 4350);
FORCEPROP 1 LAST HDL_TAP TRUE
J 2
(575 4275);
DISPLAY 1.234043 (575 4275);
PAINT GREEN (575 4275);
DISPLAY INVISIBLE (575 4275);
FORCEPROP 1 LAST PATH I20
J 2
(900 4400);
DISPLAY 0.936170 (900 4400);
PAINT GREEN (900 4400);
DISPLAY INVISIBLE (900 4400);
FORCEADD TAP..6
R 2
(900 4300);
FORCEPROP 3 LASTPIN (850 4300) SIG_NAME M_F_DQS_DN<9>
J 0
(860 4310);
DISPLAY 0.659574 (860 4310);
PAINT MONO (860 4310);
DISPLAY INVISIBLE (860 4310);
FORCEPROP 1 LASTPIN (850 4300) BN 9
J 2
(900 4310);
DISPLAY 0.617021 (900 4310);
PAINT PINK (900 4310);
FORCEPROP 2 LAST CDS_LIB mstr_standard
J 0
(900 4300);
DISPLAY 0.787234 (900 4300);
PAINT MONO (900 4300);
DISPLAY INVISIBLE (900 4300);
FORCEPROP 1 LAST BODY_TYPE PLUMBING
J 2
(900 4250);
DISPLAY 1.234043 (900 4250);
PAINT GREEN (900 4250);
DISPLAY INVISIBLE (900 4250);
FORCEPROP 1 LAST HDL_TAP TRUE
J 2
(575 4175);
DISPLAY 1.234043 (575 4175);
PAINT GREEN (575 4175);
DISPLAY INVISIBLE (575 4175);
FORCEPROP 1 LAST PATH I21
J 2
(900 4300);
DISPLAY 0.936170 (900 4300);
PAINT GREEN (900 4300);
DISPLAY INVISIBLE (900 4300);
FORCEADD TAP..6
R 2
(900 4200);
FORCEPROP 3 LASTPIN (850 4200) SIG_NAME M_F_DQS_DN<8>
J 0
(860 4210);
DISPLAY 0.659574 (860 4210);
PAINT MONO (860 4210);
DISPLAY INVISIBLE (860 4210);
FORCEPROP 1 LASTPIN (850 4200) BN 8
J 2
(900 4210);
DISPLAY 0.617021 (900 4210);
PAINT PINK (900 4210);
FORCEPROP 2 LAST CDS_LIB mstr_standard
J 0
(900 4200);
DISPLAY 0.787234 (900 4200);
PAINT MONO (900 4200);
DISPLAY INVISIBLE (900 4200);
FORCEPROP 1 LAST BODY_TYPE PLUMBING
J 2
(900 4150);
DISPLAY 1.234043 (900 4150);
PAINT GREEN (900 4150);
DISPLAY INVISIBLE (900 4150);
FORCEPROP 1 LAST HDL_TAP TRUE
J 2
(575 4075);
DISPLAY 1.234043 (575 4075);
PAINT GREEN (575 4075);
DISPLAY INVISIBLE (575 4075);
FORCEPROP 1 LAST PATH I22
J 2
(900 4200);
DISPLAY 0.936170 (900 4200);
PAINT GREEN (900 4200);
DISPLAY INVISIBLE (900 4200);
FORCEADD TAP..6
R 2
(900 4100);
FORCEPROP 3 LASTPIN (850 4100) SIG_NAME M_F_DQS_DN<7>
J 0
(860 4110);
DISPLAY 0.659574 (860 4110);
PAINT MONO (860 4110);
DISPLAY INVISIBLE (860 4110);
FORCEPROP 1 LASTPIN (850 4100) BN 7
J 2
(900 4110);
DISPLAY 0.617021 (900 4110);
PAINT PINK (900 4110);
FORCEPROP 2 LAST CDS_LIB mstr_standard
J 0
(900 4100);
DISPLAY 0.787234 (900 4100);
PAINT MONO (900 4100);
DISPLAY INVISIBLE (900 4100);
FORCEPROP 1 LAST BODY_TYPE PLUMBING
J 2
(900 4050);
DISPLAY 1.234043 (900 4050);
PAINT GREEN (900 4050);
DISPLAY INVISIBLE (900 4050);
FORCEPROP 1 LAST HDL_TAP TRUE
J 2
(575 3975);
DISPLAY 1.234043 (575 3975);
PAINT GREEN (575 3975);
DISPLAY INVISIBLE (575 3975);
FORCEPROP 1 LAST PATH I23
J 2
(900 4100);
DISPLAY 0.936170 (900 4100);
PAINT GREEN (900 4100);
DISPLAY INVISIBLE (900 4100);
FORCEADD TAP..6
R 2
(700 4450);
FORCEPROP 3 LASTPIN (650 4450) SIG_NAME M_F_DQS_DP<10>
J 0
(660 4460);
DISPLAY 0.659574 (660 4460);
PAINT MONO (660 4460);
DISPLAY INVISIBLE (660 4460);
FORCEPROP 1 LASTPIN (650 4450) BN 10
J 2
(700 4460);
DISPLAY 0.617021 (700 4460);
PAINT PINK (700 4460);
FORCEPROP 2 LAST CDS_LIB mstr_standard
J 0
(700 4450);
DISPLAY 0.787234 (700 4450);
PAINT MONO (700 4450);
DISPLAY INVISIBLE (700 4450);
FORCEPROP 1 LAST BODY_TYPE PLUMBING
J 2
(700 4400);
DISPLAY 1.234043 (700 4400);
PAINT GREEN (700 4400);
DISPLAY INVISIBLE (700 4400);
FORCEPROP 1 LAST HDL_TAP TRUE
J 2
(375 4325);
DISPLAY 1.234043 (375 4325);
PAINT GREEN (375 4325);
DISPLAY INVISIBLE (375 4325);
FORCEPROP 1 LAST PATH I24
J 2
(700 4450);
DISPLAY 0.936170 (700 4450);
PAINT GREEN (700 4450);
DISPLAY INVISIBLE (700 4450);
FORCEADD TAP..6
R 2
(700 4350);
FORCEPROP 3 LASTPIN (650 4350) SIG_NAME M_F_DQS_DP<9>
J 0
(660 4360);
DISPLAY 0.659574 (660 4360);
PAINT MONO (660 4360);
DISPLAY INVISIBLE (660 4360);
FORCEPROP 1 LASTPIN (650 4350) BN 9
J 2
(700 4360);
DISPLAY 0.617021 (700 4360);
PAINT PINK (700 4360);
FORCEPROP 2 LAST CDS_LIB mstr_standard
J 0
(700 4350);
DISPLAY 0.787234 (700 4350);
PAINT MONO (700 4350);
DISPLAY INVISIBLE (700 4350);
FORCEPROP 1 LAST BODY_TYPE PLUMBING
J 2
(700 4300);
DISPLAY 1.234043 (700 4300);
PAINT GREEN (700 4300);
DISPLAY INVISIBLE (700 4300);
FORCEPROP 1 LAST HDL_TAP TRUE
J 2
(375 4225);
DISPLAY 1.234043 (375 4225);
PAINT GREEN (375 4225);
DISPLAY INVISIBLE (375 4225);
FORCEPROP 1 LAST PATH I25
J 2
(700 4350);
DISPLAY 0.936170 (700 4350);
PAINT GREEN (700 4350);
DISPLAY INVISIBLE (700 4350);
FORCEADD TAP..6
R 2
(700 4050);
FORCEPROP 3 LASTPIN (650 4050) SIG_NAME M_F_DQS_DP<6>
J 0
(660 4060);
DISPLAY 0.659574 (660 4060);
PAINT MONO (660 4060);
DISPLAY INVISIBLE (660 4060);
FORCEPROP 1 LASTPIN (650 4050) BN 6
J 2
(700 4060);
DISPLAY 0.617021 (700 4060);
PAINT PINK (700 4060);
FORCEPROP 2 LAST CDS_LIB mstr_standard
J 0
(700 4050);
DISPLAY 0.787234 (700 4050);
PAINT MONO (700 4050);
DISPLAY INVISIBLE (700 4050);
FORCEPROP 1 LAST BODY_TYPE PLUMBING
J 2
(700 4000);
DISPLAY 1.234043 (700 4000);
PAINT GREEN (700 4000);
DISPLAY INVISIBLE (700 4000);
FORCEPROP 1 LAST HDL_TAP TRUE
J 2
(375 3925);
DISPLAY 1.234043 (375 3925);
PAINT GREEN (375 3925);
DISPLAY INVISIBLE (375 3925);
FORCEPROP 1 LAST PATH I26
J 2
(700 4050);
DISPLAY 0.936170 (700 4050);
PAINT GREEN (700 4050);
DISPLAY INVISIBLE (700 4050);
FORCEADD TAP..6
R 2
(700 4150);
FORCEPROP 3 LASTPIN (650 4150) SIG_NAME M_F_DQS_DP<7>
J 0
(660 4160);
DISPLAY 0.659574 (660 4160);
PAINT MONO (660 4160);
DISPLAY INVISIBLE (660 4160);
FORCEPROP 1 LASTPIN (650 4150) BN 7
J 2
(700 4160);
DISPLAY 0.617021 (700 4160);
PAINT PINK (700 4160);
FORCEPROP 2 LAST CDS_LIB mstr_standard
J 0
(700 4150);
DISPLAY 0.787234 (700 4150);
PAINT MONO (700 4150);
DISPLAY INVISIBLE (700 4150);
FORCEPROP 1 LAST BODY_TYPE PLUMBING
J 2
(700 4100);
DISPLAY 1.234043 (700 4100);
PAINT GREEN (700 4100);
DISPLAY INVISIBLE (700 4100);
FORCEPROP 1 LAST HDL_TAP TRUE
J 2
(375 4025);
DISPLAY 1.234043 (375 4025);
PAINT GREEN (375 4025);
DISPLAY INVISIBLE (375 4025);
FORCEPROP 1 LAST PATH I27
J 2
(700 4150);
DISPLAY 0.936170 (700 4150);
PAINT GREEN (700 4150);
DISPLAY INVISIBLE (700 4150);
FORCEADD TAP..6
R 2
(700 4250);
FORCEPROP 3 LASTPIN (650 4250) SIG_NAME M_F_DQS_DP<8>
J 0
(660 4260);
DISPLAY 0.659574 (660 4260);
PAINT MONO (660 4260);
DISPLAY INVISIBLE (660 4260);
FORCEPROP 1 LASTPIN (650 4250) BN 8
J 2
(700 4260);
DISPLAY 0.617021 (700 4260);
PAINT PINK (700 4260);
FORCEPROP 2 LAST CDS_LIB mstr_standard
J 0
(700 4250);
DISPLAY 0.787234 (700 4250);
PAINT MONO (700 4250);
DISPLAY INVISIBLE (700 4250);
FORCEPROP 1 LAST BODY_TYPE PLUMBING
J 2
(700 4200);
DISPLAY 1.234043 (700 4200);
PAINT GREEN (700 4200);
DISPLAY INVISIBLE (700 4200);
FORCEPROP 1 LAST HDL_TAP TRUE
J 2
(375 4125);
DISPLAY 1.234043 (375 4125);
PAINT GREEN (375 4125);
DISPLAY INVISIBLE (375 4125);
FORCEPROP 1 LAST PATH I28
J 2
(700 4250);
DISPLAY 0.936170 (700 4250);
PAINT GREEN (700 4250);
DISPLAY INVISIBLE (700 4250);
FORCEADD TAP..6
R 2
(900 4000);
FORCEPROP 3 LASTPIN (850 4000) SIG_NAME M_F_DQS_DN<6>
J 0
(860 4010);
DISPLAY 0.659574 (860 4010);
PAINT MONO (860 4010);
DISPLAY INVISIBLE (860 4010);
FORCEPROP 1 LASTPIN (850 4000) BN 6
J 2
(900 4010);
DISPLAY 0.617021 (900 4010);
PAINT PINK (900 4010);
FORCEPROP 2 LAST CDS_LIB mstr_standard
J 0
(900 4000);
DISPLAY 0.787234 (900 4000);
PAINT MONO (900 4000);
DISPLAY INVISIBLE (900 4000);
FORCEPROP 1 LAST BODY_TYPE PLUMBING
J 2
(900 3950);
DISPLAY 1.234043 (900 3950);
PAINT GREEN (900 3950);
DISPLAY INVISIBLE (900 3950);
FORCEPROP 1 LAST HDL_TAP TRUE
J 2
(575 3875);
DISPLAY 1.234043 (575 3875);
PAINT GREEN (575 3875);
DISPLAY INVISIBLE (575 3875);
FORCEPROP 1 LAST PATH I29
J 2
(900 4000);
DISPLAY 0.936170 (900 4000);
PAINT GREEN (900 4000);
DISPLAY INVISIBLE (900 4000);
FORCEADD TAP..6
R 2
(900 5100);
FORCEPROP 3 LASTPIN (850 5100) SIG_NAME M_F_DQS_DN<17>
J 0
(860 5110);
DISPLAY 0.659574 (860 5110);
PAINT MONO (860 5110);
DISPLAY INVISIBLE (860 5110);
FORCEPROP 1 LASTPIN (850 5100) BN 17
J 2
(900 5110);
DISPLAY 0.617021 (900 5110);
PAINT PINK (900 5110);
FORCEPROP 2 LAST CDS_LIB mstr_standard
J 2
(900 5100);
DISPLAY 0.787234 (900 5100);
PAINT MONO (900 5100);
DISPLAY INVISIBLE (900 5100);
FORCEPROP 1 LAST BODY_TYPE PLUMBING
J 2
(900 5050);
DISPLAY 1.234043 (900 5050);
PAINT GREEN (900 5050);
DISPLAY INVISIBLE (900 5050);
FORCEPROP 1 LAST HDL_TAP TRUE
J 2
(575 4975);
DISPLAY 1.234043 (575 4975);
PAINT GREEN (575 4975);
DISPLAY INVISIBLE (575 4975);
FORCEPROP 1 LAST PATH I3
J 2
(900 5100);
DISPLAY 0.936170 (900 5100);
PAINT GREEN (900 5100);
DISPLAY INVISIBLE (900 5100);
FORCEADD TAP..6
R 2
(900 3900);
FORCEPROP 3 LASTPIN (850 3900) SIG_NAME M_F_DQS_DN<5>
J 0
(860 3910);
DISPLAY 0.659574 (860 3910);
PAINT MONO (860 3910);
DISPLAY INVISIBLE (860 3910);
FORCEPROP 1 LASTPIN (850 3900) BN 5
J 2
(900 3910);
DISPLAY 0.617021 (900 3910);
PAINT PINK (900 3910);
FORCEPROP 2 LAST CDS_LIB mstr_standard
J 0
(900 3900);
DISPLAY 0.787234 (900 3900);
PAINT MONO (900 3900);
DISPLAY INVISIBLE (900 3900);
FORCEPROP 1 LAST BODY_TYPE PLUMBING
J 2
(900 3850);
DISPLAY 1.234043 (900 3850);
PAINT GREEN (900 3850);
DISPLAY INVISIBLE (900 3850);
FORCEPROP 1 LAST HDL_TAP TRUE
J 2
(575 3775);
DISPLAY 1.234043 (575 3775);
PAINT GREEN (575 3775);
DISPLAY INVISIBLE (575 3775);
FORCEPROP 1 LAST PATH I30
J 2
(900 3900);
DISPLAY 0.936170 (900 3900);
PAINT GREEN (900 3900);
DISPLAY INVISIBLE (900 3900);
FORCEADD TAP..6
R 2
(900 3800);
FORCEPROP 3 LASTPIN (850 3800) SIG_NAME M_F_DQS_DN<4>
J 0
(860 3810);
DISPLAY 0.659574 (860 3810);
PAINT MONO (860 3810);
DISPLAY INVISIBLE (860 3810);
FORCEPROP 1 LASTPIN (850 3800) BN 4
J 2
(900 3810);
DISPLAY 0.617021 (900 3810);
PAINT PINK (900 3810);
FORCEPROP 2 LAST CDS_LIB mstr_standard
J 0
(900 3800);
DISPLAY 0.787234 (900 3800);
PAINT MONO (900 3800);
DISPLAY INVISIBLE (900 3800);
FORCEPROP 1 LAST BODY_TYPE PLUMBING
J 2
(900 3750);
DISPLAY 1.234043 (900 3750);
PAINT GREEN (900 3750);
DISPLAY INVISIBLE (900 3750);
FORCEPROP 1 LAST HDL_TAP TRUE
J 2
(575 3675);
DISPLAY 1.234043 (575 3675);
PAINT GREEN (575 3675);
DISPLAY INVISIBLE (575 3675);
FORCEPROP 1 LAST PATH I31
J 2
(900 3800);
DISPLAY 0.936170 (900 3800);
PAINT GREEN (900 3800);
DISPLAY INVISIBLE (900 3800);
FORCEADD TAP..6
R 2
(900 3700);
FORCEPROP 3 LASTPIN (850 3700) SIG_NAME M_F_DQS_DN<3>
J 0
(860 3710);
DISPLAY 0.659574 (860 3710);
PAINT MONO (860 3710);
DISPLAY INVISIBLE (860 3710);
FORCEPROP 1 LASTPIN (850 3700) BN 3
J 2
(900 3710);
DISPLAY 0.617021 (900 3710);
PAINT PINK (900 3710);
FORCEPROP 2 LAST CDS_LIB mstr_standard
J 0
(900 3700);
DISPLAY 0.787234 (900 3700);
PAINT MONO (900 3700);
DISPLAY INVISIBLE (900 3700);
FORCEPROP 1 LAST BODY_TYPE PLUMBING
J 2
(900 3650);
DISPLAY 1.234043 (900 3650);
PAINT GREEN (900 3650);
DISPLAY INVISIBLE (900 3650);
FORCEPROP 1 LAST HDL_TAP TRUE
J 2
(575 3575);
DISPLAY 1.234043 (575 3575);
PAINT GREEN (575 3575);
DISPLAY INVISIBLE (575 3575);
FORCEPROP 1 LAST PATH I32
J 2
(900 3700);
DISPLAY 0.936170 (900 3700);
PAINT GREEN (900 3700);
DISPLAY INVISIBLE (900 3700);
FORCEADD TAP..6
R 2
(900 3600);
FORCEPROP 3 LASTPIN (850 3600) SIG_NAME M_F_DQS_DN<2>
J 0
(860 3610);
DISPLAY 0.659574 (860 3610);
PAINT MONO (860 3610);
DISPLAY INVISIBLE (860 3610);
FORCEPROP 1 LASTPIN (850 3600) BN 2
J 2
(900 3610);
DISPLAY 0.617021 (900 3610);
PAINT PINK (900 3610);
FORCEPROP 2 LAST CDS_LIB mstr_standard
J 0
(900 3600);
DISPLAY 0.787234 (900 3600);
PAINT MONO (900 3600);
DISPLAY INVISIBLE (900 3600);
FORCEPROP 1 LAST BODY_TYPE PLUMBING
J 2
(900 3550);
DISPLAY 1.234043 (900 3550);
PAINT GREEN (900 3550);
DISPLAY INVISIBLE (900 3550);
FORCEPROP 1 LAST HDL_TAP TRUE
J 2
(575 3475);
DISPLAY 1.234043 (575 3475);
PAINT GREEN (575 3475);
DISPLAY INVISIBLE (575 3475);
FORCEPROP 1 LAST PATH I33
J 2
(900 3600);
DISPLAY 0.936170 (900 3600);
PAINT GREEN (900 3600);
DISPLAY INVISIBLE (900 3600);
FORCEADD TAP..6
R 2
(700 3950);
FORCEPROP 3 LASTPIN (650 3950) SIG_NAME M_F_DQS_DP<5>
J 0
(660 3960);
DISPLAY 0.659574 (660 3960);
PAINT MONO (660 3960);
DISPLAY INVISIBLE (660 3960);
FORCEPROP 1 LASTPIN (650 3950) BN 5
J 2
(700 3960);
DISPLAY 0.617021 (700 3960);
PAINT PINK (700 3960);
FORCEPROP 2 LAST CDS_LIB mstr_standard
J 0
(700 3950);
DISPLAY 0.787234 (700 3950);
PAINT MONO (700 3950);
DISPLAY INVISIBLE (700 3950);
FORCEPROP 1 LAST BODY_TYPE PLUMBING
J 2
(700 3900);
DISPLAY 1.234043 (700 3900);
PAINT GREEN (700 3900);
DISPLAY INVISIBLE (700 3900);
FORCEPROP 1 LAST HDL_TAP TRUE
J 2
(375 3825);
DISPLAY 1.234043 (375 3825);
PAINT GREEN (375 3825);
DISPLAY INVISIBLE (375 3825);
FORCEPROP 1 LAST PATH I34
J 2
(700 3950);
DISPLAY 0.936170 (700 3950);
PAINT GREEN (700 3950);
DISPLAY INVISIBLE (700 3950);
FORCEADD TAP..6
R 2
(700 3850);
FORCEPROP 3 LASTPIN (650 3850) SIG_NAME M_F_DQS_DP<4>
J 0
(660 3860);
DISPLAY 0.659574 (660 3860);
PAINT MONO (660 3860);
DISPLAY INVISIBLE (660 3860);
FORCEPROP 1 LASTPIN (650 3850) BN 4
J 2
(700 3860);
DISPLAY 0.617021 (700 3860);
PAINT PINK (700 3860);
FORCEPROP 2 LAST CDS_LIB mstr_standard
J 0
(700 3850);
DISPLAY 0.787234 (700 3850);
PAINT MONO (700 3850);
DISPLAY INVISIBLE (700 3850);
FORCEPROP 1 LAST BODY_TYPE PLUMBING
J 2
(700 3800);
DISPLAY 1.234043 (700 3800);
PAINT GREEN (700 3800);
DISPLAY INVISIBLE (700 3800);
FORCEPROP 1 LAST HDL_TAP TRUE
J 2
(375 3725);
DISPLAY 1.234043 (375 3725);
PAINT GREEN (375 3725);
DISPLAY INVISIBLE (375 3725);
FORCEPROP 1 LAST PATH I35
J 2
(700 3850);
DISPLAY 0.936170 (700 3850);
PAINT GREEN (700 3850);
DISPLAY INVISIBLE (700 3850);
FORCEADD TAP..6
R 2
(700 3650);
FORCEPROP 3 LASTPIN (650 3650) SIG_NAME M_F_DQS_DP<2>
J 0
(660 3660);
DISPLAY 0.659574 (660 3660);
PAINT MONO (660 3660);
DISPLAY INVISIBLE (660 3660);
FORCEPROP 1 LASTPIN (650 3650) BN 2
J 2
(700 3660);
DISPLAY 0.617021 (700 3660);
PAINT PINK (700 3660);
FORCEPROP 2 LAST CDS_LIB mstr_standard
J 0
(700 3650);
DISPLAY 0.787234 (700 3650);
PAINT MONO (700 3650);
DISPLAY INVISIBLE (700 3650);
FORCEPROP 1 LAST BODY_TYPE PLUMBING
J 2
(700 3600);
DISPLAY 1.234043 (700 3600);
PAINT GREEN (700 3600);
DISPLAY INVISIBLE (700 3600);
FORCEPROP 1 LAST HDL_TAP TRUE
J 2
(375 3525);
DISPLAY 1.234043 (375 3525);
PAINT GREEN (375 3525);
DISPLAY INVISIBLE (375 3525);
FORCEPROP 1 LAST PATH I36
J 2
(700 3650);
DISPLAY 0.936170 (700 3650);
PAINT GREEN (700 3650);
DISPLAY INVISIBLE (700 3650);
FORCEADD TAP..6
R 2
(700 3550);
FORCEPROP 3 LASTPIN (650 3550) SIG_NAME M_F_DQS_DP<1>
J 0
(660 3560);
DISPLAY 0.659574 (660 3560);
PAINT MONO (660 3560);
DISPLAY INVISIBLE (660 3560);
FORCEPROP 1 LASTPIN (650 3550) BN 1
J 2
(700 3560);
DISPLAY 0.617021 (700 3560);
PAINT PINK (700 3560);
FORCEPROP 2 LAST CDS_LIB mstr_standard
J 0
(700 3550);
DISPLAY 0.787234 (700 3550);
PAINT MONO (700 3550);
DISPLAY INVISIBLE (700 3550);
FORCEPROP 1 LAST BODY_TYPE PLUMBING
J 2
(700 3500);
DISPLAY 1.234043 (700 3500);
PAINT GREEN (700 3500);
DISPLAY INVISIBLE (700 3500);
FORCEPROP 1 LAST HDL_TAP TRUE
J 2
(375 3425);
DISPLAY 1.234043 (375 3425);
PAINT GREEN (375 3425);
DISPLAY INVISIBLE (375 3425);
FORCEPROP 1 LAST PATH I37
J 2
(700 3550);
DISPLAY 0.936170 (700 3550);
PAINT GREEN (700 3550);
DISPLAY INVISIBLE (700 3550);
FORCEADD TAP..6
R 2
(700 3750);
FORCEPROP 3 LASTPIN (650 3750) SIG_NAME M_F_DQS_DP<3>
J 0
(660 3760);
DISPLAY 0.659574 (660 3760);
PAINT MONO (660 3760);
DISPLAY INVISIBLE (660 3760);
FORCEPROP 1 LASTPIN (650 3750) BN 3
J 2
(700 3760);
DISPLAY 0.617021 (700 3760);
PAINT PINK (700 3760);
FORCEPROP 2 LAST CDS_LIB mstr_standard
J 0
(700 3750);
DISPLAY 0.787234 (700 3750);
PAINT MONO (700 3750);
DISPLAY INVISIBLE (700 3750);
FORCEPROP 1 LAST BODY_TYPE PLUMBING
J 2
(700 3700);
DISPLAY 1.234043 (700 3700);
PAINT GREEN (700 3700);
DISPLAY INVISIBLE (700 3700);
FORCEPROP 1 LAST HDL_TAP TRUE
J 2
(375 3625);
DISPLAY 1.234043 (375 3625);
PAINT GREEN (375 3625);
DISPLAY INVISIBLE (375 3625);
FORCEPROP 1 LAST PATH I38
J 2
(700 3750);
DISPLAY 0.936170 (700 3750);
PAINT GREEN (700 3750);
DISPLAY INVISIBLE (700 3750);
FORCEADD TAP..6
R 2
(900 3400);
FORCEPROP 3 LASTPIN (850 3400) SIG_NAME M_F_DQS_DN<0>
J 0
(860 3410);
DISPLAY 0.659574 (860 3410);
PAINT MONO (860 3410);
DISPLAY INVISIBLE (860 3410);
FORCEPROP 1 LASTPIN (850 3400) BN 0
J 2
(900 3410);
DISPLAY 0.617021 (900 3410);
PAINT PINK (900 3410);
FORCEPROP 2 LAST CDS_LIB mstr_standard
J 0
(900 3400);
DISPLAY 0.787234 (900 3400);
PAINT MONO (900 3400);
DISPLAY INVISIBLE (900 3400);
FORCEPROP 1 LAST BODY_TYPE PLUMBING
J 2
(900 3350);
DISPLAY 1.234043 (900 3350);
PAINT GREEN (900 3350);
DISPLAY INVISIBLE (900 3350);
FORCEPROP 1 LAST HDL_TAP TRUE
J 2
(575 3275);
DISPLAY 1.234043 (575 3275);
PAINT GREEN (575 3275);
DISPLAY INVISIBLE (575 3275);
FORCEPROP 1 LAST PATH I39
J 2
(900 3400);
DISPLAY 0.936170 (900 3400);
PAINT GREEN (900 3400);
DISPLAY INVISIBLE (900 3400);
FORCEADD TAP..6
R 2
(700 5150);
FORCEPROP 3 LASTPIN (650 5150) SIG_NAME M_F_DQS_DP<17>
J 0
(660 5160);
DISPLAY 0.659574 (660 5160);
PAINT MONO (660 5160);
DISPLAY INVISIBLE (660 5160);
FORCEPROP 1 LASTPIN (650 5150) BN 17
J 2
(700 5160);
DISPLAY 0.617021 (700 5160);
PAINT PINK (700 5160);
FORCEPROP 2 LAST CDS_LIB mstr_standard
J 2
(700 5150);
DISPLAY 0.787234 (700 5150);
PAINT MONO (700 5150);
DISPLAY INVISIBLE (700 5150);
FORCEPROP 1 LAST BODY_TYPE PLUMBING
J 2
(700 5100);
DISPLAY 1.234043 (700 5100);
PAINT GREEN (700 5100);
DISPLAY INVISIBLE (700 5100);
FORCEPROP 1 LAST HDL_TAP TRUE
J 2
(375 5025);
DISPLAY 1.234043 (375 5025);
PAINT GREEN (375 5025);
DISPLAY INVISIBLE (375 5025);
FORCEPROP 1 LAST PATH I4
J 2
(700 5150);
DISPLAY 0.936170 (700 5150);
PAINT GREEN (700 5150);
DISPLAY INVISIBLE (700 5150);
FORCEADD TAP..6
R 2
(900 3500);
FORCEPROP 3 LASTPIN (850 3500) SIG_NAME M_F_DQS_DN<1>
J 0
(860 3510);
DISPLAY 0.659574 (860 3510);
PAINT MONO (860 3510);
DISPLAY INVISIBLE (860 3510);
FORCEPROP 1 LASTPIN (850 3500) BN 1
J 2
(900 3510);
DISPLAY 0.617021 (900 3510);
PAINT PINK (900 3510);
FORCEPROP 2 LAST CDS_LIB mstr_standard
J 0
(900 3500);
DISPLAY 0.787234 (900 3500);
PAINT MONO (900 3500);
DISPLAY INVISIBLE (900 3500);
FORCEPROP 1 LAST BODY_TYPE PLUMBING
J 2
(900 3450);
DISPLAY 1.234043 (900 3450);
PAINT GREEN (900 3450);
DISPLAY INVISIBLE (900 3450);
FORCEPROP 1 LAST HDL_TAP TRUE
J 2
(575 3375);
DISPLAY 1.234043 (575 3375);
PAINT GREEN (575 3375);
DISPLAY INVISIBLE (575 3375);
FORCEPROP 1 LAST PATH I40
J 2
(900 3500);
DISPLAY 0.936170 (900 3500);
PAINT GREEN (900 3500);
DISPLAY INVISIBLE (900 3500);
FORCEADD TAP..6
R 2
(700 3450);
FORCEPROP 3 LASTPIN (650 3450) SIG_NAME M_F_DQS_DP<0>
J 0
(660 3460);
DISPLAY 0.659574 (660 3460);
PAINT MONO (660 3460);
DISPLAY INVISIBLE (660 3460);
FORCEPROP 1 LASTPIN (650 3450) BN 0
J 2
(700 3460);
DISPLAY 0.617021 (700 3460);
PAINT PINK (700 3460);
FORCEPROP 2 LAST CDS_LIB mstr_standard
J 0
(700 3450);
DISPLAY 0.787234 (700 3450);
PAINT MONO (700 3450);
DISPLAY INVISIBLE (700 3450);
FORCEPROP 1 LAST BODY_TYPE PLUMBING
J 2
(700 3400);
DISPLAY 1.234043 (700 3400);
PAINT GREEN (700 3400);
DISPLAY INVISIBLE (700 3400);
FORCEPROP 1 LAST HDL_TAP TRUE
J 2
(375 3325);
DISPLAY 1.234043 (375 3325);
PAINT GREEN (375 3325);
DISPLAY INVISIBLE (375 3325);
FORCEPROP 1 LAST PATH I41
J 2
(700 3450);
DISPLAY 0.936170 (700 3450);
PAINT GREEN (700 3450);
DISPLAY INVISIBLE (700 3450);
FORCEADD SCONN288_H44441003..3
(1800 2550);
FORCEPROP 1 LAST LOCATION J6L1
J 0
(1350 3950);
DISPLAY 0.617021 (1350 3950);
PAINT AQUA (1350 3950);
FORCEPROP 1 LAST PART_NUMBER H44441-003
J 0
(1350 1200);
DISPLAY 0.617021 (1350 1200);
PAINT BLUE (1350 1200);
FORCEPROP 1 LAST MATERIAL SCONN
J 0
(1350 3900);
DISPLAY 0.617021 (1350 3900);
PAINT SKYBLUE (1350 3900);
FORCEPROP 2 LASTPIN (1300 3700) $PN 2
J 2
(1290 3710);
DISPLAY 0.617021 (1290 3710);
PAINT ORANGE (1290 3710);
FORCEPROP 2 LASTPIN (1300 3650) $PN 4
J 2
(1290 3660);
DISPLAY 0.617021 (1290 3660);
PAINT ORANGE (1290 3660);
FORCEPROP 2 LASTPIN (1300 3600) $PN 6
J 2
(1290 3610);
DISPLAY 0.617021 (1290 3610);
PAINT ORANGE (1290 3610);
FORCEPROP 2 LASTPIN (1300 3550) $PN 9
J 2
(1290 3560);
DISPLAY 0.617021 (1290 3560);
PAINT ORANGE (1290 3560);
FORCEPROP 2 LASTPIN (1300 3500) $PN 11
J 2
(1290 3510);
DISPLAY 0.617021 (1290 3510);
PAINT ORANGE (1290 3510);
FORCEPROP 2 LASTPIN (1300 3450) $PN 13
J 2
(1290 3460);
DISPLAY 0.617021 (1290 3460);
PAINT ORANGE (1290 3460);
FORCEPROP 2 LASTPIN (1300 3400) $PN 15
J 2
(1290 3410);
DISPLAY 0.617021 (1290 3410);
PAINT ORANGE (1290 3410);
FORCEPROP 2 LASTPIN (1300 3350) $PN 17
J 2
(1290 3360);
DISPLAY 0.617021 (1290 3360);
PAINT ORANGE (1290 3360);
FORCEPROP 2 LASTPIN (1300 3300) $PN 20
J 2
(1290 3310);
DISPLAY 0.617021 (1290 3310);
PAINT ORANGE (1290 3310);
FORCEPROP 2 LASTPIN (1300 3250) $PN 22
J 2
(1290 3260);
DISPLAY 0.617021 (1290 3260);
PAINT ORANGE (1290 3260);
FORCEPROP 2 LASTPIN (1300 3200) $PN 24
J 2
(1290 3210);
DISPLAY 0.617021 (1290 3210);
PAINT ORANGE (1290 3210);
FORCEPROP 2 LASTPIN (1300 3150) $PN 26
J 2
(1290 3160);
DISPLAY 0.617021 (1290 3160);
PAINT ORANGE (1290 3160);
FORCEPROP 2 LASTPIN (1300 3100) $PN 28
J 2
(1290 3110);
DISPLAY 0.617021 (1290 3110);
PAINT ORANGE (1290 3110);
FORCEPROP 2 LASTPIN (1300 3050) $PN 31
J 2
(1290 3060);
DISPLAY 0.617021 (1290 3060);
PAINT ORANGE (1290 3060);
FORCEPROP 2 LASTPIN (1300 3000) $PN 33
J 2
(1290 3010);
DISPLAY 0.617021 (1290 3010);
PAINT ORANGE (1290 3010);
FORCEPROP 2 LASTPIN (1300 2950) $PN 35
J 2
(1290 2960);
DISPLAY 0.617021 (1290 2960);
PAINT ORANGE (1290 2960);
FORCEPROP 2 LASTPIN (1300 2900) $PN 37
J 2
(1290 2910);
DISPLAY 0.617021 (1290 2910);
PAINT ORANGE (1290 2910);
FORCEPROP 2 LASTPIN (1300 2850) $PN 39
J 2
(1290 2860);
DISPLAY 0.617021 (1290 2860);
PAINT ORANGE (1290 2860);
FORCEPROP 2 LASTPIN (1300 2800) $PN 42
J 2
(1290 2810);
DISPLAY 0.617021 (1290 2810);
PAINT ORANGE (1290 2810);
FORCEPROP 2 LASTPIN (1300 2750) $PN 44
J 2
(1290 2760);
DISPLAY 0.617021 (1290 2760);
PAINT ORANGE (1290 2760);
FORCEPROP 2 LASTPIN (1300 2700) $PN 46
J 2
(1290 2710);
DISPLAY 0.617021 (1290 2710);
PAINT ORANGE (1290 2710);
FORCEPROP 2 LASTPIN (1300 2650) $PN 48
J 2
(1290 2660);
DISPLAY 0.617021 (1290 2660);
PAINT ORANGE (1290 2660);
FORCEPROP 2 LASTPIN (1300 2600) $PN 50
J 2
(1290 2610);
DISPLAY 0.617021 (1290 2610);
PAINT ORANGE (1290 2610);
FORCEPROP 2 LASTPIN (1300 2550) $PN 53
J 2
(1290 2560);
DISPLAY 0.617021 (1290 2560);
PAINT ORANGE (1290 2560);
FORCEPROP 2 LASTPIN (1300 2500) $PN 55
J 2
(1290 2510);
DISPLAY 0.617021 (1290 2510);
PAINT ORANGE (1290 2510);
FORCEPROP 2 LASTPIN (1300 2450) $PN 57
J 2
(1290 2460);
DISPLAY 0.617021 (1290 2460);
PAINT ORANGE (1290 2460);
FORCEPROP 2 LASTPIN (1300 2400) $PN 94
J 2
(1290 2410);
DISPLAY 0.617021 (1290 2410);
PAINT ORANGE (1290 2410);
FORCEPROP 2 LASTPIN (1300 2350) $PN 96
J 2
(1290 2360);
DISPLAY 0.617021 (1290 2360);
PAINT ORANGE (1290 2360);
FORCEPROP 2 LASTPIN (1300 2300) $PN 98
J 2
(1290 2310);
DISPLAY 0.617021 (1290 2310);
PAINT ORANGE (1290 2310);
FORCEPROP 2 LASTPIN (1300 2250) $PN 101
J 2
(1290 2260);
DISPLAY 0.617021 (1290 2260);
PAINT ORANGE (1290 2260);
FORCEPROP 2 LASTPIN (1300 2200) $PN 103
J 2
(1290 2210);
DISPLAY 0.617021 (1290 2210);
PAINT ORANGE (1290 2210);
FORCEPROP 2 LASTPIN (1300 2150) $PN 105
J 2
(1290 2160);
DISPLAY 0.617021 (1290 2160);
PAINT ORANGE (1290 2160);
FORCEPROP 2 LASTPIN (1300 2100) $PN 107
J 2
(1290 2110);
DISPLAY 0.617021 (1290 2110);
PAINT ORANGE (1290 2110);
FORCEPROP 2 LASTPIN (1300 2050) $PN 109
J 2
(1290 2060);
DISPLAY 0.617021 (1290 2060);
PAINT ORANGE (1290 2060);
FORCEPROP 2 LASTPIN (1300 2000) $PN 112
J 2
(1290 2010);
DISPLAY 0.617021 (1290 2010);
PAINT ORANGE (1290 2010);
FORCEPROP 2 LASTPIN (1300 1950) $PN 114
J 2
(1290 1960);
DISPLAY 0.617021 (1290 1960);
PAINT ORANGE (1290 1960);
FORCEPROP 2 LASTPIN (1300 1900) $PN 116
J 2
(1290 1910);
DISPLAY 0.617021 (1290 1910);
PAINT ORANGE (1290 1910);
FORCEPROP 2 LASTPIN (1300 1850) $PN 118
J 2
(1290 1860);
DISPLAY 0.617021 (1290 1860);
PAINT ORANGE (1290 1860);
FORCEPROP 2 LASTPIN (1300 1800) $PN 120
J 2
(1290 1810);
DISPLAY 0.617021 (1290 1810);
PAINT ORANGE (1290 1810);
FORCEPROP 2 LASTPIN (1300 1750) $PN 123
J 2
(1290 1760);
DISPLAY 0.617021 (1290 1760);
PAINT ORANGE (1290 1760);
FORCEPROP 2 LASTPIN (1300 1700) $PN 125
J 2
(1290 1710);
DISPLAY 0.617021 (1290 1710);
PAINT ORANGE (1290 1710);
FORCEPROP 2 LASTPIN (1300 1650) $PN 127
J 2
(1290 1660);
DISPLAY 0.617021 (1290 1660);
PAINT ORANGE (1290 1660);
FORCEPROP 2 LASTPIN (1300 1600) $PN 129
J 2
(1290 1610);
DISPLAY 0.617021 (1290 1610);
PAINT ORANGE (1290 1610);
FORCEPROP 2 LASTPIN (1300 1550) $PN 131
J 2
(1290 1560);
DISPLAY 0.617021 (1290 1560);
PAINT ORANGE (1290 1560);
FORCEPROP 2 LASTPIN (1300 1500) $PN 134
J 2
(1290 1510);
DISPLAY 0.617021 (1290 1510);
PAINT ORANGE (1290 1510);
FORCEPROP 2 LASTPIN (1300 1450) $PN 136
J 2
(1290 1460);
DISPLAY 0.617021 (1290 1460);
PAINT ORANGE (1290 1460);
FORCEPROP 2 LASTPIN (1300 1400) $PN 138
J 2
(1290 1410);
DISPLAY 0.617021 (1290 1410);
PAINT ORANGE (1290 1410);
FORCEPROP 2 LASTPIN (2300 3700) $PN 147
J 0
(2310 3710);
DISPLAY 0.617021 (2310 3710);
PAINT ORANGE (2310 3710);
FORCEPROP 2 LASTPIN (2300 3650) $PN 149
J 0
(2310 3660);
DISPLAY 0.617021 (2310 3660);
PAINT ORANGE (2310 3660);
FORCEPROP 2 LASTPIN (2300 3600) $PN 151
J 0
(2310 3610);
DISPLAY 0.617021 (2310 3610);
PAINT ORANGE (2310 3610);
FORCEPROP 2 LASTPIN (2300 3550) $PN 154
J 0
(2310 3560);
DISPLAY 0.617021 (2310 3560);
PAINT ORANGE (2310 3560);
FORCEPROP 2 LASTPIN (2300 3500) $PN 156
J 0
(2310 3510);
DISPLAY 0.617021 (2310 3510);
PAINT ORANGE (2310 3510);
FORCEPROP 2 LASTPIN (2300 3450) $PN 158
J 0
(2310 3460);
DISPLAY 0.617021 (2310 3460);
PAINT ORANGE (2310 3460);
FORCEPROP 2 LASTPIN (2300 3400) $PN 160
J 0
(2310 3410);
DISPLAY 0.617021 (2310 3410);
PAINT ORANGE (2310 3410);
FORCEPROP 2 LASTPIN (2300 3350) $PN 162
J 0
(2310 3360);
DISPLAY 0.617021 (2310 3360);
PAINT ORANGE (2310 3360);
FORCEPROP 2 LASTPIN (2300 3300) $PN 165
J 0
(2310 3310);
DISPLAY 0.617021 (2310 3310);
PAINT ORANGE (2310 3310);
FORCEPROP 2 LASTPIN (2300 3250) $PN 167
J 0
(2310 3260);
DISPLAY 0.617021 (2310 3260);
PAINT ORANGE (2310 3260);
FORCEPROP 2 LASTPIN (2300 3200) $PN 169
J 0
(2310 3210);
DISPLAY 0.617021 (2310 3210);
PAINT ORANGE (2310 3210);
FORCEPROP 2 LASTPIN (2300 3150) $PN 171
J 0
(2310 3160);
DISPLAY 0.617021 (2310 3160);
PAINT ORANGE (2310 3160);
FORCEPROP 2 LASTPIN (2300 3100) $PN 173
J 0
(2310 3110);
DISPLAY 0.617021 (2310 3110);
PAINT ORANGE (2310 3110);
FORCEPROP 2 LASTPIN (2300 3050) $PN 176
J 0
(2310 3060);
DISPLAY 0.617021 (2310 3060);
PAINT ORANGE (2310 3060);
FORCEPROP 2 LASTPIN (2300 3000) $PN 178
J 0
(2310 3010);
DISPLAY 0.617021 (2310 3010);
PAINT ORANGE (2310 3010);
FORCEPROP 2 LASTPIN (2300 2950) $PN 180
J 0
(2310 2960);
DISPLAY 0.617021 (2310 2960);
PAINT ORANGE (2310 2960);
FORCEPROP 2 LASTPIN (2300 2900) $PN 182
J 0
(2310 2910);
DISPLAY 0.617021 (2310 2910);
PAINT ORANGE (2310 2910);
FORCEPROP 2 LASTPIN (2300 2850) $PN 184
J 0
(2310 2860);
DISPLAY 0.617021 (2310 2860);
PAINT ORANGE (2310 2860);
FORCEPROP 2 LASTPIN (2300 2800) $PN 187
J 0
(2310 2810);
DISPLAY 0.617021 (2310 2810);
PAINT ORANGE (2310 2810);
FORCEPROP 2 LASTPIN (2300 2750) $PN 189
J 0
(2310 2760);
DISPLAY 0.617021 (2310 2760);
PAINT ORANGE (2310 2760);
FORCEPROP 2 LASTPIN (2300 2700) $PN 191
J 0
(2310 2710);
DISPLAY 0.617021 (2310 2710);
PAINT ORANGE (2310 2710);
FORCEPROP 2 LASTPIN (2300 2650) $PN 193
J 0
(2310 2660);
DISPLAY 0.617021 (2310 2660);
PAINT ORANGE (2310 2660);
FORCEPROP 2 LASTPIN (2300 2600) $PN 195
J 0
(2310 2610);
DISPLAY 0.617021 (2310 2610);
PAINT ORANGE (2310 2610);
FORCEPROP 2 LASTPIN (2300 2550) $PN 198
J 0
(2310 2560);
DISPLAY 0.617021 (2310 2560);
PAINT ORANGE (2310 2560);
FORCEPROP 2 LASTPIN (2300 2500) $PN 200
J 0
(2310 2510);
DISPLAY 0.617021 (2310 2510);
PAINT ORANGE (2310 2510);
FORCEPROP 2 LASTPIN (2300 2450) $PN 202
J 0
(2310 2460);
DISPLAY 0.617021 (2310 2460);
PAINT ORANGE (2310 2460);
FORCEPROP 2 LASTPIN (2300 2400) $PN 239
J 0
(2310 2410);
DISPLAY 0.617021 (2310 2410);
PAINT ORANGE (2310 2410);
FORCEPROP 2 LASTPIN (2300 2350) $PN 241
J 0
(2310 2360);
DISPLAY 0.617021 (2310 2360);
PAINT ORANGE (2310 2360);
FORCEPROP 2 LASTPIN (2300 2300) $PN 243
J 0
(2310 2310);
DISPLAY 0.617021 (2310 2310);
PAINT ORANGE (2310 2310);
FORCEPROP 2 LASTPIN (2300 2250) $PN 246
J 0
(2310 2260);
DISPLAY 0.617021 (2310 2260);
PAINT ORANGE (2310 2260);
FORCEPROP 2 LASTPIN (2300 2200) $PN 248
J 0
(2310 2210);
DISPLAY 0.617021 (2310 2210);
PAINT ORANGE (2310 2210);
FORCEPROP 2 LASTPIN (2300 2150) $PN 250
J 0
(2310 2160);
DISPLAY 0.617021 (2310 2160);
PAINT ORANGE (2310 2160);
FORCEPROP 2 LASTPIN (2300 2100) $PN 252
J 0
(2310 2110);
DISPLAY 0.617021 (2310 2110);
PAINT ORANGE (2310 2110);
FORCEPROP 2 LASTPIN (2300 2050) $PN 254
J 0
(2310 2060);
DISPLAY 0.617021 (2310 2060);
PAINT ORANGE (2310 2060);
FORCEPROP 2 LASTPIN (2300 2000) $PN 257
J 0
(2310 2010);
DISPLAY 0.617021 (2310 2010);
PAINT ORANGE (2310 2010);
FORCEPROP 2 LASTPIN (2300 1950) $PN 259
J 0
(2310 1960);
DISPLAY 0.617021 (2310 1960);
PAINT ORANGE (2310 1960);
FORCEPROP 2 LASTPIN (2300 1900) $PN 261
J 0
(2310 1910);
DISPLAY 0.617021 (2310 1910);
PAINT ORANGE (2310 1910);
FORCEPROP 2 LASTPIN (2300 1850) $PN 263
J 0
(2310 1860);
DISPLAY 0.617021 (2310 1860);
PAINT ORANGE (2310 1860);
FORCEPROP 2 LASTPIN (2300 1800) $PN 265
J 0
(2310 1810);
DISPLAY 0.617021 (2310 1810);
PAINT ORANGE (2310 1810);
FORCEPROP 2 LASTPIN (2300 1750) $PN 268
J 0
(2310 1760);
DISPLAY 0.617021 (2310 1760);
PAINT ORANGE (2310 1760);
FORCEPROP 2 LASTPIN (2300 1700) $PN 270
J 0
(2310 1710);
DISPLAY 0.617021 (2310 1710);
PAINT ORANGE (2310 1710);
FORCEPROP 2 LASTPIN (2300 1650) $PN 272
J 0
(2310 1660);
DISPLAY 0.617021 (2310 1660);
PAINT ORANGE (2310 1660);
FORCEPROP 2 LASTPIN (2300 1600) $PN 274
J 0
(2310 1610);
DISPLAY 0.617021 (2310 1610);
PAINT ORANGE (2310 1610);
FORCEPROP 2 LASTPIN (2300 1550) $PN 276
J 0
(2310 1560);
DISPLAY 0.617021 (2310 1560);
PAINT ORANGE (2310 1560);
FORCEPROP 2 LASTPIN (2300 1500) $PN 279
J 0
(2310 1510);
DISPLAY 0.617021 (2310 1510);
PAINT ORANGE (2310 1510);
FORCEPROP 2 LASTPIN (2300 1450) $PN 281
J 0
(2310 1460);
DISPLAY 0.617021 (2310 1460);
PAINT ORANGE (2310 1460);
FORCEPROP 2 LASTPIN (2300 1400) $PN 283
J 0
(2310 1410);
DISPLAY 0.617021 (2310 1410);
PAINT ORANGE (2310 1410);
FORCEPROP 1 LAST PACK_TYPE PIP
J 0
(1350 4000);
PAINT SKYBLUE (1350 4000);
DISPLAY INVISIBLE (1350 4000);
FORCEPROP 2 LAST BOM_COST MEM
J 0
(1800 2550);
PAINT ORANGE (1800 2550);
DISPLAY INVISIBLE (1800 2550);
FORCEPROP 2 LAST CDS_LIB mstr_sconn
J 0
(1800 2550);
PAINT ORANGE (1800 2550);
DISPLAY INVISIBLE (1800 2550);
FORCEPROP 2 LAST SEC_TYPE PIP
J 0
(1350 4000);
DISPLAY 1.021277 (1350 4000);
PAINT ORANGE (1350 4000);
DISPLAY INVISIBLE (1350 4000);
FORCEPROP 2 LAST SEC 3
J 0
(1350 4000);
DISPLAY 0.680851 (1350 4000);
PAINT MONO (1350 4000);
DISPLAY INVISIBLE (1350 4000);
FORCEPROP 2 LAST CDS_LOCATION J6L1
J 0
(1350 3950);
DISPLAY 0.617021 (1350 3950);
PAINT AQUA (1350 3950);
DISPLAY INVISIBLE (1350 3950);
FORCEPROP 1 LAST PATH I43
J 0
(1800 3900);
PAINT GREEN (1800 3900);
DISPLAY INVISIBLE (1800 3900);
FORCEPROP 2 LAST ROOM DDR4_CH_F1
J 0
(1800 2550);
PAINT ORANGE (1800 2550);
DISPLAY INVISIBLE (1800 2550);
FORCEADD GND..1
R 2
(1100 1250);
FORCEPROP 3 LASTPIN (1100 1300) SIG_NAME GND\g
J 0
(1110 1310);
DISPLAY 0.659574 (1110 1310);
PAINT MONO (1110 1310);
DISPLAY INVISIBLE (1110 1310);
FORCEPROP 1 LAST VOLTAGE 0
J 0
(1100 1250);
PAINT SKYBLUE (1100 1250);
DISPLAY INVISIBLE (1100 1250);
FORCEPROP 2 LAST CDS_LIB mstr_symbols
J 0
(1100 1250);
DISPLAY 0.787234 (1100 1250);
PAINT MONO (1100 1250);
DISPLAY INVISIBLE (1100 1250);
FORCEPROP 1 LAST SIZE 1B
J 2
(1025 1200);
DISPLAY 1.170213 (1025 1200);
PAINT GREEN (1025 1200);
DISPLAY INVISIBLE (1025 1200);
FORCEPROP 2 LAST BOM_COST MEM
J 0
(1100 1255);
PAINT ORANGE (1100 1255);
DISPLAY INVISIBLE (1100 1255);
FORCEPROP 1 LAST BODY_TYPE PLUMBING
J 2
(1145 1207);
DISPLAY 0.340426 (1145 1207);
PAINT GREEN (1145 1207);
DISPLAY INVISIBLE (1145 1207);
FORCEPROP 1 LAST PATH I44
J 2
(1025 1250);
DISPLAY 0.936170 (1025 1250);
PAINT GREEN (1025 1250);
DISPLAY INVISIBLE (1025 1250);
FORCEPROP 2 LAST ROOM DDR4_CH_C
J 0
(1100 1255);
PAINT ORANGE (1100 1255);
DISPLAY INVISIBLE (1100 1255);
FORCEPROP 1 LAST HDL_POWER GND
J 2
(1100 1400);
DISPLAY 0.553191 (1100 1400);
PAINT GREEN (1100 1400);
DISPLAY INVISIBLE (1100 1400);
FORCEADD OFFPAGE..3
(-1100 4800);
FORCEPROP 2 LAST $XR0 28 
J 0
(-886 4800);
DISPLAY 0.638298 (-886 4800);
PAINT MONO (-886 4800);
FORCEPROP 2 LAST $XR1 53 
J 0
(-796 4800);
DISPLAY 0.638298 (-796 4800);
PAINT MONO (-796 4800);
FORCEPROP 2 LAST CDS_LIB mstr_standard
J 0
(-1100 4800);
DISPLAY 0.787234 (-1100 4800);
PAINT MONO (-1100 4800);
DISPLAY INVISIBLE (-1100 4800);
FORCEPROP 1 LAST OFFPAGE TRUE
J 0
(-775 4675);
DISPLAY 0.936170 (-775 4675);
PAINT GREEN (-775 4675);
DISPLAY INVISIBLE (-775 4675);
FORCEPROP 1 LAST COMMENT_BODY TRUE
J 0
(-1150 4700);
DISPLAY 0.936170 (-1150 4700);
PAINT GREEN (-1150 4700);
DISPLAY INVISIBLE (-1150 4700);
FORCEPROP 2 LAST PATH I45
J 0
(-900 4875);
DISPLAY 0.787234 (-900 4875);
PAINT MONO (-900 4875);
DISPLAY INVISIBLE (-900 4875);
FORCEADD TAP..6
R 2
(-1650 4650);
FORCEPROP 3 LASTPIN (-1700 4650) SIG_NAME M_F_DQ<61>
J 0
(-1690 4660);
DISPLAY 0.659574 (-1690 4660);
PAINT MONO (-1690 4660);
DISPLAY INVISIBLE (-1690 4660);
FORCEPROP 1 LASTPIN (-1700 4650) BN 61
J 2
(-1650 4660);
DISPLAY 0.617021 (-1650 4660);
PAINT PINK (-1650 4660);
FORCEPROP 2 LAST CDS_LIB mstr_standard
J 2
(-1650 4650);
DISPLAY 0.787234 (-1650 4650);
PAINT MONO (-1650 4650);
DISPLAY INVISIBLE (-1650 4650);
FORCEPROP 1 LAST BODY_TYPE PLUMBING
J 2
(-1650 4600);
DISPLAY 1.234043 (-1650 4600);
PAINT GREEN (-1650 4600);
DISPLAY INVISIBLE (-1650 4600);
FORCEPROP 1 LAST HDL_TAP TRUE
J 2
(-1975 4525);
DISPLAY 1.234043 (-1975 4525);
PAINT GREEN (-1975 4525);
DISPLAY INVISIBLE (-1975 4525);
FORCEPROP 1 LAST PATH I46
J 2
(-1650 4650);
DISPLAY 0.936170 (-1650 4650);
PAINT GREEN (-1650 4650);
DISPLAY INVISIBLE (-1650 4650);
FORCEADD TAP..6
R 2
(-1650 4600);
FORCEPROP 3 LASTPIN (-1700 4600) SIG_NAME M_F_DQ<60>
J 0
(-1690 4610);
DISPLAY 0.659574 (-1690 4610);
PAINT MONO (-1690 4610);
DISPLAY INVISIBLE (-1690 4610);
FORCEPROP 1 LASTPIN (-1700 4600) BN 60
J 2
(-1650 4610);
DISPLAY 0.617021 (-1650 4610);
PAINT PINK (-1650 4610);
FORCEPROP 2 LAST CDS_LIB mstr_standard
J 2
(-1650 4600);
DISPLAY 0.787234 (-1650 4600);
PAINT MONO (-1650 4600);
DISPLAY INVISIBLE (-1650 4600);
FORCEPROP 1 LAST BODY_TYPE PLUMBING
J 2
(-1650 4550);
DISPLAY 1.234043 (-1650 4550);
PAINT GREEN (-1650 4550);
DISPLAY INVISIBLE (-1650 4550);
FORCEPROP 1 LAST HDL_TAP TRUE
J 2
(-1975 4475);
DISPLAY 1.234043 (-1975 4475);
PAINT GREEN (-1975 4475);
DISPLAY INVISIBLE (-1975 4475);
FORCEPROP 1 LAST PATH I47
J 2
(-1650 4600);
DISPLAY 0.936170 (-1650 4600);
PAINT GREEN (-1650 4600);
DISPLAY INVISIBLE (-1650 4600);
FORCEADD TAP..6
R 2
(-1650 4700);
FORCEPROP 3 LASTPIN (-1700 4700) SIG_NAME M_F_DQ<62>
J 0
(-1690 4710);
DISPLAY 0.659574 (-1690 4710);
PAINT MONO (-1690 4710);
DISPLAY INVISIBLE (-1690 4710);
FORCEPROP 1 LASTPIN (-1700 4700) BN 62
J 2
(-1650 4710);
DISPLAY 0.617021 (-1650 4710);
PAINT PINK (-1650 4710);
FORCEPROP 2 LAST CDS_LIB mstr_standard
J 2
(-1650 4700);
DISPLAY 0.787234 (-1650 4700);
PAINT MONO (-1650 4700);
DISPLAY INVISIBLE (-1650 4700);
FORCEPROP 1 LAST BODY_TYPE PLUMBING
J 2
(-1650 4650);
DISPLAY 1.234043 (-1650 4650);
PAINT GREEN (-1650 4650);
DISPLAY INVISIBLE (-1650 4650);
FORCEPROP 1 LAST HDL_TAP TRUE
J 2
(-1975 4575);
DISPLAY 1.234043 (-1975 4575);
PAINT GREEN (-1975 4575);
DISPLAY INVISIBLE (-1975 4575);
FORCEPROP 1 LAST PATH I48
J 2
(-1650 4700);
DISPLAY 0.936170 (-1650 4700);
PAINT GREEN (-1650 4700);
DISPLAY INVISIBLE (-1650 4700);
FORCEADD TAP..6
R 2
(-1650 4750);
FORCEPROP 3 LASTPIN (-1700 4750) SIG_NAME M_F_DQ<63>
J 0
(-1690 4760);
DISPLAY 0.659574 (-1690 4760);
PAINT MONO (-1690 4760);
DISPLAY INVISIBLE (-1690 4760);
FORCEPROP 1 LASTPIN (-1700 4750) BN 63
J 2
(-1650 4760);
DISPLAY 0.617021 (-1650 4760);
PAINT PINK (-1650 4760);
FORCEPROP 2 LAST CDS_LIB mstr_standard
J 2
(-1650 4750);
DISPLAY 0.787234 (-1650 4750);
PAINT MONO (-1650 4750);
DISPLAY INVISIBLE (-1650 4750);
FORCEPROP 1 LAST BODY_TYPE PLUMBING
J 2
(-1650 4700);
DISPLAY 1.234043 (-1650 4700);
PAINT GREEN (-1650 4700);
DISPLAY INVISIBLE (-1650 4700);
FORCEPROP 1 LAST HDL_TAP TRUE
J 2
(-1975 4625);
DISPLAY 1.234043 (-1975 4625);
PAINT GREEN (-1975 4625);
DISPLAY INVISIBLE (-1975 4625);
FORCEPROP 1 LAST PATH I49
J 2
(-1650 4750);
DISPLAY 0.936170 (-1650 4750);
PAINT GREEN (-1650 4750);
DISPLAY INVISIBLE (-1650 4750);
FORCEADD TAP..6
R 2
(900 5000);
FORCEPROP 3 LASTPIN (850 5000) SIG_NAME M_F_DQS_DN<16>
J 0
(860 5010);
DISPLAY 0.659574 (860 5010);
PAINT MONO (860 5010);
DISPLAY INVISIBLE (860 5010);
FORCEPROP 1 LASTPIN (850 5000) BN 16
J 2
(900 5010);
DISPLAY 0.617021 (900 5010);
PAINT PINK (900 5010);
FORCEPROP 2 LAST CDS_LIB mstr_standard
J 0
(900 5000);
DISPLAY 0.787234 (900 5000);
PAINT MONO (900 5000);
DISPLAY INVISIBLE (900 5000);
FORCEPROP 1 LAST BODY_TYPE PLUMBING
J 2
(900 4950);
DISPLAY 1.234043 (900 4950);
PAINT GREEN (900 4950);
DISPLAY INVISIBLE (900 4950);
FORCEPROP 1 LAST HDL_TAP TRUE
J 2
(575 4875);
DISPLAY 1.234043 (575 4875);
PAINT GREEN (575 4875);
DISPLAY INVISIBLE (575 4875);
FORCEPROP 1 LAST PATH I5
J 2
(900 5000);
DISPLAY 0.936170 (900 5000);
PAINT GREEN (900 5000);
DISPLAY INVISIBLE (900 5000);
FORCEADD TAP..6
R 2
(-1650 4350);
FORCEPROP 3 LASTPIN (-1700 4350) SIG_NAME M_F_DQ<55>
J 0
(-1690 4360);
DISPLAY 0.659574 (-1690 4360);
PAINT MONO (-1690 4360);
DISPLAY INVISIBLE (-1690 4360);
FORCEPROP 1 LASTPIN (-1700 4350) BN 55
J 2
(-1650 4360);
DISPLAY 0.617021 (-1650 4360);
PAINT PINK (-1650 4360);
FORCEPROP 2 LAST CDS_LIB mstr_standard
J 2
(-1650 4350);
DISPLAY 0.787234 (-1650 4350);
PAINT MONO (-1650 4350);
DISPLAY INVISIBLE (-1650 4350);
FORCEPROP 1 LAST BODY_TYPE PLUMBING
J 2
(-1650 4300);
DISPLAY 1.234043 (-1650 4300);
PAINT GREEN (-1650 4300);
DISPLAY INVISIBLE (-1650 4300);
FORCEPROP 1 LAST HDL_TAP TRUE
J 2
(-1975 4225);
DISPLAY 1.234043 (-1975 4225);
PAINT GREEN (-1975 4225);
DISPLAY INVISIBLE (-1975 4225);
FORCEPROP 1 LAST PATH I50
J 2
(-1650 4350);
DISPLAY 0.936170 (-1650 4350);
PAINT GREEN (-1650 4350);
DISPLAY INVISIBLE (-1650 4350);
FORCEADD TAP..6
R 2
(-1650 4400);
FORCEPROP 3 LASTPIN (-1700 4400) SIG_NAME M_F_DQ<56>
J 0
(-1690 4410);
DISPLAY 0.659574 (-1690 4410);
PAINT MONO (-1690 4410);
DISPLAY INVISIBLE (-1690 4410);
FORCEPROP 1 LASTPIN (-1700 4400) BN 56
J 2
(-1650 4410);
DISPLAY 0.617021 (-1650 4410);
PAINT PINK (-1650 4410);
FORCEPROP 2 LAST CDS_LIB mstr_standard
J 2
(-1650 4400);
DISPLAY 0.787234 (-1650 4400);
PAINT MONO (-1650 4400);
DISPLAY INVISIBLE (-1650 4400);
FORCEPROP 1 LAST BODY_TYPE PLUMBING
J 2
(-1650 4350);
DISPLAY 1.234043 (-1650 4350);
PAINT GREEN (-1650 4350);
DISPLAY INVISIBLE (-1650 4350);
FORCEPROP 1 LAST HDL_TAP TRUE
J 2
(-1975 4275);
DISPLAY 1.234043 (-1975 4275);
PAINT GREEN (-1975 4275);
DISPLAY INVISIBLE (-1975 4275);
FORCEPROP 1 LAST PATH I51
J 2
(-1650 4400);
DISPLAY 0.936170 (-1650 4400);
PAINT GREEN (-1650 4400);
DISPLAY INVISIBLE (-1650 4400);
FORCEADD TAP..6
R 2
(-1650 4500);
FORCEPROP 3 LASTPIN (-1700 4500) SIG_NAME M_F_DQ<58>
J 0
(-1690 4510);
DISPLAY 0.659574 (-1690 4510);
PAINT MONO (-1690 4510);
DISPLAY INVISIBLE (-1690 4510);
FORCEPROP 1 LASTPIN (-1700 4500) BN 58
J 2
(-1650 4510);
DISPLAY 0.617021 (-1650 4510);
PAINT PINK (-1650 4510);
FORCEPROP 2 LAST CDS_LIB mstr_standard
J 2
(-1650 4500);
DISPLAY 0.787234 (-1650 4500);
PAINT MONO (-1650 4500);
DISPLAY INVISIBLE (-1650 4500);
FORCEPROP 1 LAST BODY_TYPE PLUMBING
J 2
(-1650 4450);
DISPLAY 1.234043 (-1650 4450);
PAINT GREEN (-1650 4450);
DISPLAY INVISIBLE (-1650 4450);
FORCEPROP 1 LAST HDL_TAP TRUE
J 2
(-1975 4375);
DISPLAY 1.234043 (-1975 4375);
PAINT GREEN (-1975 4375);
DISPLAY INVISIBLE (-1975 4375);
FORCEPROP 1 LAST PATH I52
J 2
(-1650 4500);
DISPLAY 0.936170 (-1650 4500);
PAINT GREEN (-1650 4500);
DISPLAY INVISIBLE (-1650 4500);
FORCEADD TAP..6
R 2
(-1650 4450);
FORCEPROP 3 LASTPIN (-1700 4450) SIG_NAME M_F_DQ<57>
J 0
(-1690 4460);
DISPLAY 0.659574 (-1690 4460);
PAINT MONO (-1690 4460);
DISPLAY INVISIBLE (-1690 4460);
FORCEPROP 1 LASTPIN (-1700 4450) BN 57
J 2
(-1650 4460);
DISPLAY 0.617021 (-1650 4460);
PAINT PINK (-1650 4460);
FORCEPROP 2 LAST CDS_LIB mstr_standard
J 2
(-1650 4450);
DISPLAY 0.787234 (-1650 4450);
PAINT MONO (-1650 4450);
DISPLAY INVISIBLE (-1650 4450);
FORCEPROP 1 LAST BODY_TYPE PLUMBING
J 2
(-1650 4400);
DISPLAY 1.234043 (-1650 4400);
PAINT GREEN (-1650 4400);
DISPLAY INVISIBLE (-1650 4400);
FORCEPROP 1 LAST HDL_TAP TRUE
J 2
(-1975 4325);
DISPLAY 1.234043 (-1975 4325);
PAINT GREEN (-1975 4325);
DISPLAY INVISIBLE (-1975 4325);
FORCEPROP 1 LAST PATH I53
J 2
(-1650 4450);
DISPLAY 0.936170 (-1650 4450);
PAINT GREEN (-1650 4450);
DISPLAY INVISIBLE (-1650 4450);
FORCEADD TAP..6
R 2
(-1650 4550);
FORCEPROP 3 LASTPIN (-1700 4550) SIG_NAME M_F_DQ<59>
J 0
(-1690 4560);
DISPLAY 0.659574 (-1690 4560);
PAINT MONO (-1690 4560);
DISPLAY INVISIBLE (-1690 4560);
FORCEPROP 1 LASTPIN (-1700 4550) BN 59
J 2
(-1650 4560);
DISPLAY 0.617021 (-1650 4560);
PAINT PINK (-1650 4560);
FORCEPROP 2 LAST CDS_LIB mstr_standard
J 2
(-1650 4550);
DISPLAY 0.787234 (-1650 4550);
PAINT MONO (-1650 4550);
DISPLAY INVISIBLE (-1650 4550);
FORCEPROP 1 LAST BODY_TYPE PLUMBING
J 2
(-1650 4500);
DISPLAY 1.234043 (-1650 4500);
PAINT GREEN (-1650 4500);
DISPLAY INVISIBLE (-1650 4500);
FORCEPROP 1 LAST HDL_TAP TRUE
J 2
(-1975 4425);
DISPLAY 1.234043 (-1975 4425);
PAINT GREEN (-1975 4425);
DISPLAY INVISIBLE (-1975 4425);
FORCEPROP 1 LAST PATH I54
J 2
(-1650 4550);
DISPLAY 0.936170 (-1650 4550);
PAINT GREEN (-1650 4550);
DISPLAY INVISIBLE (-1650 4550);
FORCEADD TAP..6
R 2
(-1650 4100);
FORCEPROP 3 LASTPIN (-1700 4100) SIG_NAME M_F_DQ<50>
J 0
(-1690 4110);
DISPLAY 0.659574 (-1690 4110);
PAINT MONO (-1690 4110);
DISPLAY INVISIBLE (-1690 4110);
FORCEPROP 1 LASTPIN (-1700 4100) BN 50
J 2
(-1650 4110);
DISPLAY 0.617021 (-1650 4110);
PAINT PINK (-1650 4110);
FORCEPROP 2 LAST CDS_LIB mstr_standard
J 2
(-1650 4100);
DISPLAY 0.787234 (-1650 4100);
PAINT MONO (-1650 4100);
DISPLAY INVISIBLE (-1650 4100);
FORCEPROP 1 LAST BODY_TYPE PLUMBING
J 2
(-1650 4050);
DISPLAY 1.234043 (-1650 4050);
PAINT GREEN (-1650 4050);
DISPLAY INVISIBLE (-1650 4050);
FORCEPROP 1 LAST HDL_TAP TRUE
J 2
(-1975 3975);
DISPLAY 1.234043 (-1975 3975);
PAINT GREEN (-1975 3975);
DISPLAY INVISIBLE (-1975 3975);
FORCEPROP 1 LAST PATH I55
J 2
(-1650 4100);
DISPLAY 0.936170 (-1650 4100);
PAINT GREEN (-1650 4100);
DISPLAY INVISIBLE (-1650 4100);
FORCEADD TAP..6
R 2
(-1650 4150);
FORCEPROP 3 LASTPIN (-1700 4150) SIG_NAME M_F_DQ<51>
J 0
(-1690 4160);
DISPLAY 0.659574 (-1690 4160);
PAINT MONO (-1690 4160);
DISPLAY INVISIBLE (-1690 4160);
FORCEPROP 1 LASTPIN (-1700 4150) BN 51
J 2
(-1650 4160);
DISPLAY 0.617021 (-1650 4160);
PAINT PINK (-1650 4160);
FORCEPROP 2 LAST CDS_LIB mstr_standard
J 2
(-1650 4150);
DISPLAY 0.787234 (-1650 4150);
PAINT MONO (-1650 4150);
DISPLAY INVISIBLE (-1650 4150);
FORCEPROP 1 LAST BODY_TYPE PLUMBING
J 2
(-1650 4100);
DISPLAY 1.234043 (-1650 4100);
PAINT GREEN (-1650 4100);
DISPLAY INVISIBLE (-1650 4100);
FORCEPROP 1 LAST HDL_TAP TRUE
J 2
(-1975 4025);
DISPLAY 1.234043 (-1975 4025);
PAINT GREEN (-1975 4025);
DISPLAY INVISIBLE (-1975 4025);
FORCEPROP 1 LAST PATH I56
J 2
(-1650 4150);
DISPLAY 0.936170 (-1650 4150);
PAINT GREEN (-1650 4150);
DISPLAY INVISIBLE (-1650 4150);
FORCEADD TAP..6
R 2
(-1650 4200);
FORCEPROP 3 LASTPIN (-1700 4200) SIG_NAME M_F_DQ<52>
J 0
(-1690 4210);
DISPLAY 0.659574 (-1690 4210);
PAINT MONO (-1690 4210);
DISPLAY INVISIBLE (-1690 4210);
FORCEPROP 1 LASTPIN (-1700 4200) BN 52
J 2
(-1650 4210);
DISPLAY 0.617021 (-1650 4210);
PAINT PINK (-1650 4210);
FORCEPROP 2 LAST CDS_LIB mstr_standard
J 2
(-1650 4200);
DISPLAY 0.787234 (-1650 4200);
PAINT MONO (-1650 4200);
DISPLAY INVISIBLE (-1650 4200);
FORCEPROP 1 LAST BODY_TYPE PLUMBING
J 2
(-1650 4150);
DISPLAY 1.234043 (-1650 4150);
PAINT GREEN (-1650 4150);
DISPLAY INVISIBLE (-1650 4150);
FORCEPROP 1 LAST HDL_TAP TRUE
J 2
(-1975 4075);
DISPLAY 1.234043 (-1975 4075);
PAINT GREEN (-1975 4075);
DISPLAY INVISIBLE (-1975 4075);
FORCEPROP 1 LAST PATH I57
J 2
(-1650 4200);
DISPLAY 0.936170 (-1650 4200);
PAINT GREEN (-1650 4200);
DISPLAY INVISIBLE (-1650 4200);
FORCEADD TAP..6
R 2
(-1650 4300);
FORCEPROP 3 LASTPIN (-1700 4300) SIG_NAME M_F_DQ<54>
J 0
(-1690 4310);
DISPLAY 0.659574 (-1690 4310);
PAINT MONO (-1690 4310);
DISPLAY INVISIBLE (-1690 4310);
FORCEPROP 1 LASTPIN (-1700 4300) BN 54
J 2
(-1650 4310);
DISPLAY 0.617021 (-1650 4310);
PAINT PINK (-1650 4310);
FORCEPROP 2 LAST CDS_LIB mstr_standard
J 2
(-1650 4300);
DISPLAY 0.787234 (-1650 4300);
PAINT MONO (-1650 4300);
DISPLAY INVISIBLE (-1650 4300);
FORCEPROP 1 LAST BODY_TYPE PLUMBING
J 2
(-1650 4250);
DISPLAY 1.234043 (-1650 4250);
PAINT GREEN (-1650 4250);
DISPLAY INVISIBLE (-1650 4250);
FORCEPROP 1 LAST HDL_TAP TRUE
J 2
(-1975 4175);
DISPLAY 1.234043 (-1975 4175);
PAINT GREEN (-1975 4175);
DISPLAY INVISIBLE (-1975 4175);
FORCEPROP 1 LAST PATH I58
J 2
(-1650 4300);
DISPLAY 0.936170 (-1650 4300);
PAINT GREEN (-1650 4300);
DISPLAY INVISIBLE (-1650 4300);
FORCEADD TAP..6
R 2
(-1650 4250);
FORCEPROP 3 LASTPIN (-1700 4250) SIG_NAME M_F_DQ<53>
J 0
(-1690 4260);
DISPLAY 0.659574 (-1690 4260);
PAINT MONO (-1690 4260);
DISPLAY INVISIBLE (-1690 4260);
FORCEPROP 1 LASTPIN (-1700 4250) BN 53
J 2
(-1650 4260);
DISPLAY 0.617021 (-1650 4260);
PAINT PINK (-1650 4260);
FORCEPROP 2 LAST CDS_LIB mstr_standard
J 2
(-1650 4250);
DISPLAY 0.787234 (-1650 4250);
PAINT MONO (-1650 4250);
DISPLAY INVISIBLE (-1650 4250);
FORCEPROP 1 LAST BODY_TYPE PLUMBING
J 2
(-1650 4200);
DISPLAY 1.234043 (-1650 4200);
PAINT GREEN (-1650 4200);
DISPLAY INVISIBLE (-1650 4200);
FORCEPROP 1 LAST HDL_TAP TRUE
J 2
(-1975 4125);
DISPLAY 1.234043 (-1975 4125);
PAINT GREEN (-1975 4125);
DISPLAY INVISIBLE (-1975 4125);
FORCEPROP 1 LAST PATH I59
J 2
(-1650 4250);
DISPLAY 0.936170 (-1650 4250);
PAINT GREEN (-1650 4250);
DISPLAY INVISIBLE (-1650 4250);
FORCEADD TAP..6
R 2
(900 4900);
FORCEPROP 3 LASTPIN (850 4900) SIG_NAME M_F_DQS_DN<15>
J 0
(860 4910);
DISPLAY 0.659574 (860 4910);
PAINT MONO (860 4910);
DISPLAY INVISIBLE (860 4910);
FORCEPROP 1 LASTPIN (850 4900) BN 15
J 2
(900 4910);
DISPLAY 0.617021 (900 4910);
PAINT PINK (900 4910);
FORCEPROP 2 LAST CDS_LIB mstr_standard
J 0
(900 4900);
DISPLAY 0.787234 (900 4900);
PAINT MONO (900 4900);
DISPLAY INVISIBLE (900 4900);
FORCEPROP 1 LAST BODY_TYPE PLUMBING
J 2
(900 4850);
DISPLAY 1.234043 (900 4850);
PAINT GREEN (900 4850);
DISPLAY INVISIBLE (900 4850);
FORCEPROP 1 LAST HDL_TAP TRUE
J 2
(575 4775);
DISPLAY 1.234043 (575 4775);
PAINT GREEN (575 4775);
DISPLAY INVISIBLE (575 4775);
FORCEPROP 1 LAST PATH I6
J 2
(900 4900);
DISPLAY 0.936170 (900 4900);
PAINT GREEN (900 4900);
DISPLAY INVISIBLE (900 4900);
FORCEADD TAP..6
R 2
(-1650 3800);
FORCEPROP 3 LASTPIN (-1700 3800) SIG_NAME M_F_DQ<44>
J 0
(-1690 3810);
DISPLAY 0.659574 (-1690 3810);
PAINT MONO (-1690 3810);
DISPLAY INVISIBLE (-1690 3810);
FORCEPROP 1 LASTPIN (-1700 3800) BN 44
J 2
(-1650 3810);
DISPLAY 0.617021 (-1650 3810);
PAINT PINK (-1650 3810);
FORCEPROP 2 LAST CDS_LIB mstr_standard
J 2
(-1650 3800);
DISPLAY 0.787234 (-1650 3800);
PAINT MONO (-1650 3800);
DISPLAY INVISIBLE (-1650 3800);
FORCEPROP 1 LAST BODY_TYPE PLUMBING
J 2
(-1650 3750);
DISPLAY 1.234043 (-1650 3750);
PAINT GREEN (-1650 3750);
DISPLAY INVISIBLE (-1650 3750);
FORCEPROP 1 LAST HDL_TAP TRUE
J 2
(-1975 3675);
DISPLAY 1.234043 (-1975 3675);
PAINT GREEN (-1975 3675);
DISPLAY INVISIBLE (-1975 3675);
FORCEPROP 1 LAST PATH I60
J 2
(-1650 3800);
DISPLAY 0.936170 (-1650 3800);
PAINT GREEN (-1650 3800);
DISPLAY INVISIBLE (-1650 3800);
FORCEADD TAP..6
R 2
(-1650 3850);
FORCEPROP 3 LASTPIN (-1700 3850) SIG_NAME M_F_DQ<45>
J 0
(-1690 3860);
DISPLAY 0.659574 (-1690 3860);
PAINT MONO (-1690 3860);
DISPLAY INVISIBLE (-1690 3860);
FORCEPROP 1 LASTPIN (-1700 3850) BN 45
J 2
(-1650 3860);
DISPLAY 0.617021 (-1650 3860);
PAINT PINK (-1650 3860);
FORCEPROP 2 LAST CDS_LIB mstr_standard
J 2
(-1650 3850);
DISPLAY 0.787234 (-1650 3850);
PAINT MONO (-1650 3850);
DISPLAY INVISIBLE (-1650 3850);
FORCEPROP 1 LAST BODY_TYPE PLUMBING
J 2
(-1650 3800);
DISPLAY 1.234043 (-1650 3800);
PAINT GREEN (-1650 3800);
DISPLAY INVISIBLE (-1650 3800);
FORCEPROP 1 LAST HDL_TAP TRUE
J 2
(-1975 3725);
DISPLAY 1.234043 (-1975 3725);
PAINT GREEN (-1975 3725);
DISPLAY INVISIBLE (-1975 3725);
FORCEPROP 1 LAST PATH I61
J 2
(-1650 3850);
DISPLAY 0.936170 (-1650 3850);
PAINT GREEN (-1650 3850);
DISPLAY INVISIBLE (-1650 3850);
FORCEADD TAP..6
R 2
(-1650 3900);
FORCEPROP 3 LASTPIN (-1700 3900) SIG_NAME M_F_DQ<46>
J 0
(-1690 3910);
DISPLAY 0.659574 (-1690 3910);
PAINT MONO (-1690 3910);
DISPLAY INVISIBLE (-1690 3910);
FORCEPROP 1 LASTPIN (-1700 3900) BN 46
J 2
(-1650 3910);
DISPLAY 0.617021 (-1650 3910);
PAINT PINK (-1650 3910);
FORCEPROP 2 LAST CDS_LIB mstr_standard
J 2
(-1650 3900);
DISPLAY 0.787234 (-1650 3900);
PAINT MONO (-1650 3900);
DISPLAY INVISIBLE (-1650 3900);
FORCEPROP 1 LAST BODY_TYPE PLUMBING
J 2
(-1650 3850);
DISPLAY 1.234043 (-1650 3850);
PAINT GREEN (-1650 3850);
DISPLAY INVISIBLE (-1650 3850);
FORCEPROP 1 LAST HDL_TAP TRUE
J 2
(-1975 3775);
DISPLAY 1.234043 (-1975 3775);
PAINT GREEN (-1975 3775);
DISPLAY INVISIBLE (-1975 3775);
FORCEPROP 1 LAST PATH I62
J 2
(-1650 3900);
DISPLAY 0.936170 (-1650 3900);
PAINT GREEN (-1650 3900);
DISPLAY INVISIBLE (-1650 3900);
FORCEADD TAP..6
R 2
(-1650 4000);
FORCEPROP 3 LASTPIN (-1700 4000) SIG_NAME M_F_DQ<48>
J 0
(-1690 4010);
DISPLAY 0.659574 (-1690 4010);
PAINT MONO (-1690 4010);
DISPLAY INVISIBLE (-1690 4010);
FORCEPROP 1 LASTPIN (-1700 4000) BN 48
J 2
(-1650 4010);
DISPLAY 0.617021 (-1650 4010);
PAINT PINK (-1650 4010);
FORCEPROP 2 LAST CDS_LIB mstr_standard
J 2
(-1650 4000);
DISPLAY 0.787234 (-1650 4000);
PAINT MONO (-1650 4000);
DISPLAY INVISIBLE (-1650 4000);
FORCEPROP 1 LAST BODY_TYPE PLUMBING
J 2
(-1650 3950);
DISPLAY 1.234043 (-1650 3950);
PAINT GREEN (-1650 3950);
DISPLAY INVISIBLE (-1650 3950);
FORCEPROP 1 LAST HDL_TAP TRUE
J 2
(-1975 3875);
DISPLAY 1.234043 (-1975 3875);
PAINT GREEN (-1975 3875);
DISPLAY INVISIBLE (-1975 3875);
FORCEPROP 1 LAST PATH I63
J 2
(-1650 4000);
DISPLAY 0.936170 (-1650 4000);
PAINT GREEN (-1650 4000);
DISPLAY INVISIBLE (-1650 4000);
FORCEADD TAP..6
R 2
(-1650 3950);
FORCEPROP 3 LASTPIN (-1700 3950) SIG_NAME M_F_DQ<47>
J 0
(-1690 3960);
DISPLAY 0.659574 (-1690 3960);
PAINT MONO (-1690 3960);
DISPLAY INVISIBLE (-1690 3960);
FORCEPROP 1 LASTPIN (-1700 3950) BN 47
J 2
(-1650 3960);
DISPLAY 0.617021 (-1650 3960);
PAINT PINK (-1650 3960);
FORCEPROP 2 LAST CDS_LIB mstr_standard
J 2
(-1650 3950);
DISPLAY 0.787234 (-1650 3950);
PAINT MONO (-1650 3950);
DISPLAY INVISIBLE (-1650 3950);
FORCEPROP 1 LAST BODY_TYPE PLUMBING
J 2
(-1650 3900);
DISPLAY 1.234043 (-1650 3900);
PAINT GREEN (-1650 3900);
DISPLAY INVISIBLE (-1650 3900);
FORCEPROP 1 LAST HDL_TAP TRUE
J 2
(-1975 3825);
DISPLAY 1.234043 (-1975 3825);
PAINT GREEN (-1975 3825);
DISPLAY INVISIBLE (-1975 3825);
FORCEPROP 1 LAST PATH I64
J 2
(-1650 3950);
DISPLAY 0.936170 (-1650 3950);
PAINT GREEN (-1650 3950);
DISPLAY INVISIBLE (-1650 3950);
FORCEADD TAP..6
R 2
(-1650 4050);
FORCEPROP 3 LASTPIN (-1700 4050) SIG_NAME M_F_DQ<49>
J 0
(-1690 4060);
DISPLAY 0.659574 (-1690 4060);
PAINT MONO (-1690 4060);
DISPLAY INVISIBLE (-1690 4060);
FORCEPROP 1 LASTPIN (-1700 4050) BN 49
J 2
(-1650 4060);
DISPLAY 0.617021 (-1650 4060);
PAINT PINK (-1650 4060);
FORCEPROP 2 LAST CDS_LIB mstr_standard
J 2
(-1650 4050);
DISPLAY 0.787234 (-1650 4050);
PAINT MONO (-1650 4050);
DISPLAY INVISIBLE (-1650 4050);
FORCEPROP 1 LAST BODY_TYPE PLUMBING
J 2
(-1650 4000);
DISPLAY 1.234043 (-1650 4000);
PAINT GREEN (-1650 4000);
DISPLAY INVISIBLE (-1650 4000);
FORCEPROP 1 LAST HDL_TAP TRUE
J 2
(-1975 3925);
DISPLAY 1.234043 (-1975 3925);
PAINT GREEN (-1975 3925);
DISPLAY INVISIBLE (-1975 3925);
FORCEPROP 1 LAST PATH I65
J 2
(-1650 4050);
DISPLAY 0.936170 (-1650 4050);
PAINT GREEN (-1650 4050);
DISPLAY INVISIBLE (-1650 4050);
FORCEADD SCONN288_H44441003..2
(0 4300);
FORCEPROP 1 LAST LOCATION J6L1
J 0
(-400 5400);
DISPLAY 0.617021 (-400 5400);
PAINT AQUA (-400 5400);
FORCEPROP 1 LAST PART_NUMBER H44441-003
J 0
(-400 3200);
DISPLAY 0.617021 (-400 3200);
PAINT BLUE (-400 3200);
FORCEPROP 1 LAST MATERIAL SCONN
J 0
(-400 5350);
DISPLAY 0.617021 (-400 5350);
PAINT SKYBLUE (-400 5350);
FORCEPROP 2 LASTPIN (450 5150) $PN 51
J 0
(460 5160);
DISPLAY 0.617021 (460 5160);
PAINT ORANGE (460 5160);
FORCEPROP 2 LASTPIN (450 5100) $PN 52
J 0
(460 5110);
DISPLAY 0.617021 (460 5110);
PAINT ORANGE (460 5110);
FORCEPROP 2 LASTPIN (450 5050) $PN 132
J 0
(460 5060);
DISPLAY 0.617021 (460 5060);
PAINT ORANGE (460 5060);
FORCEPROP 2 LASTPIN (450 5000) $PN 133
J 0
(460 5010);
DISPLAY 0.617021 (460 5010);
PAINT ORANGE (460 5010);
FORCEPROP 2 LASTPIN (450 4950) $PN 121
J 0
(460 4960);
DISPLAY 0.617021 (460 4960);
PAINT ORANGE (460 4960);
FORCEPROP 2 LASTPIN (450 4900) $PN 122
J 0
(460 4910);
DISPLAY 0.617021 (460 4910);
PAINT ORANGE (460 4910);
FORCEPROP 2 LASTPIN (450 4850) $PN 110
J 0
(460 4860);
DISPLAY 0.617021 (460 4860);
PAINT ORANGE (460 4860);
FORCEPROP 2 LASTPIN (450 4800) $PN 111
J 0
(460 4810);
DISPLAY 0.617021 (460 4810);
PAINT ORANGE (460 4810);
FORCEPROP 2 LASTPIN (450 4750) $PN 99
J 0
(460 4760);
DISPLAY 0.617021 (460 4760);
PAINT ORANGE (460 4760);
FORCEPROP 2 LASTPIN (450 4700) $PN 100
J 0
(460 4710);
DISPLAY 0.617021 (460 4710);
PAINT ORANGE (460 4710);
FORCEPROP 2 LASTPIN (450 4650) $PN 40
J 0
(460 4660);
DISPLAY 0.617021 (460 4660);
PAINT ORANGE (460 4660);
FORCEPROP 2 LASTPIN (450 4600) $PN 41
J 0
(460 4610);
DISPLAY 0.617021 (460 4610);
PAINT ORANGE (460 4610);
FORCEPROP 2 LASTPIN (450 4550) $PN 29
J 0
(460 4560);
DISPLAY 0.617021 (460 4560);
PAINT ORANGE (460 4560);
FORCEPROP 2 LASTPIN (450 4500) $PN 30
J 0
(460 4510);
DISPLAY 0.617021 (460 4510);
PAINT ORANGE (460 4510);
FORCEPROP 2 LASTPIN (450 4450) $PN 18
J 0
(460 4460);
DISPLAY 0.617021 (460 4460);
PAINT ORANGE (460 4460);
FORCEPROP 2 LASTPIN (450 4400) $PN 19
J 0
(460 4410);
DISPLAY 0.617021 (460 4410);
PAINT ORANGE (460 4410);
FORCEPROP 2 LASTPIN (450 4350) $PN 7
J 0
(460 4360);
DISPLAY 0.617021 (460 4360);
PAINT ORANGE (460 4360);
FORCEPROP 2 LASTPIN (450 4300) $PN 8
J 0
(460 4310);
DISPLAY 0.617021 (460 4310);
PAINT ORANGE (460 4310);
FORCEPROP 2 LASTPIN (450 4250) $PN 197
J 0
(460 4260);
DISPLAY 0.617021 (460 4260);
PAINT ORANGE (460 4260);
FORCEPROP 2 LASTPIN (450 4200) $PN 196
J 0
(460 4210);
DISPLAY 0.617021 (460 4210);
PAINT ORANGE (460 4210);
FORCEPROP 2 LASTPIN (450 4150) $PN 278
J 0
(460 4160);
DISPLAY 0.617021 (460 4160);
PAINT ORANGE (460 4160);
FORCEPROP 2 LASTPIN (450 4100) $PN 277
J 0
(460 4110);
DISPLAY 0.617021 (460 4110);
PAINT ORANGE (460 4110);
FORCEPROP 2 LASTPIN (450 4050) $PN 267
J 0
(460 4060);
DISPLAY 0.617021 (460 4060);
PAINT ORANGE (460 4060);
FORCEPROP 2 LASTPIN (450 4000) $PN 266
J 0
(460 4010);
DISPLAY 0.617021 (460 4010);
PAINT ORANGE (460 4010);
FORCEPROP 2 LASTPIN (450 3950) $PN 256
J 0
(460 3960);
DISPLAY 0.617021 (460 3960);
PAINT ORANGE (460 3960);
FORCEPROP 2 LASTPIN (450 3900) $PN 255
J 0
(460 3910);
DISPLAY 0.617021 (460 3910);
PAINT ORANGE (460 3910);
FORCEPROP 2 LASTPIN (450 3850) $PN 245
J 0
(460 3860);
DISPLAY 0.617021 (460 3860);
PAINT ORANGE (460 3860);
FORCEPROP 2 LASTPIN (450 3800) $PN 244
J 0
(460 3810);
DISPLAY 0.617021 (460 3810);
PAINT ORANGE (460 3810);
FORCEPROP 2 LASTPIN (450 3750) $PN 186
J 0
(460 3760);
DISPLAY 0.617021 (460 3760);
PAINT ORANGE (460 3760);
FORCEPROP 2 LASTPIN (450 3700) $PN 185
J 0
(460 3710);
DISPLAY 0.617021 (460 3710);
PAINT ORANGE (460 3710);
FORCEPROP 2 LASTPIN (450 3650) $PN 175
J 0
(460 3660);
DISPLAY 0.617021 (460 3660);
PAINT ORANGE (460 3660);
FORCEPROP 2 LASTPIN (450 3600) $PN 174
J 0
(460 3610);
DISPLAY 0.617021 (460 3610);
PAINT ORANGE (460 3610);
FORCEPROP 2 LASTPIN (450 3550) $PN 164
J 0
(460 3560);
DISPLAY 0.617021 (460 3560);
PAINT ORANGE (460 3560);
FORCEPROP 2 LASTPIN (450 3500) $PN 163
J 0
(460 3510);
DISPLAY 0.617021 (460 3510);
PAINT ORANGE (460 3510);
FORCEPROP 2 LASTPIN (450 3450) $PN 153
J 0
(460 3460);
DISPLAY 0.617021 (460 3460);
PAINT ORANGE (460 3460);
FORCEPROP 2 LASTPIN (450 3400) $PN 152
J 0
(460 3410);
DISPLAY 0.617021 (460 3410);
PAINT ORANGE (460 3410);
FORCEPROP 1 LAST PACK_TYPE PIP
J 0
(-400 5450);
PAINT SKYBLUE (-400 5450);
DISPLAY INVISIBLE (-400 5450);
FORCEPROP 2 LAST BOM_COST MEM
J 0
(0 4300);
PAINT ORANGE (0 4300);
DISPLAY INVISIBLE (0 4300);
FORCEPROP 2 LAST CDS_LIB mstr_sconn
J 0
(0 4300);
PAINT ORANGE (0 4300);
DISPLAY INVISIBLE (0 4300);
FORCEPROP 2 LAST SEC_TYPE PIP
J 0
(-400 5450);
DISPLAY 1.021277 (-400 5450);
PAINT ORANGE (-400 5450);
DISPLAY INVISIBLE (-400 5450);
FORCEPROP 2 LAST SEC 2
J 0
(-400 5450);
DISPLAY 0.680851 (-400 5450);
PAINT MONO (-400 5450);
DISPLAY INVISIBLE (-400 5450);
FORCEPROP 2 LAST CDS_LOCATION J6L1
J 0
(-400 5400);
DISPLAY 0.617021 (-400 5400);
PAINT AQUA (-400 5400);
DISPLAY INVISIBLE (-400 5400);
FORCEPROP 1 LAST PATH I66
J 0
(0 5350);
PAINT GREEN (0 5350);
DISPLAY INVISIBLE (0 5350);
FORCEPROP 2 LAST ROOM DDR4_CH_F1
J 0
(-400 5500);
PAINT ORANGE (-400 5500);
DISPLAY INVISIBLE (-400 5500);
FORCEADD TAP..6
R 2
(-1650 3650);
FORCEPROP 3 LASTPIN (-1700 3650) SIG_NAME M_F_DQ<41>
J 0
(-1690 3660);
DISPLAY 0.659574 (-1690 3660);
PAINT MONO (-1690 3660);
DISPLAY INVISIBLE (-1690 3660);
FORCEPROP 1 LASTPIN (-1700 3650) BN 41
J 2
(-1650 3660);
DISPLAY 0.617021 (-1650 3660);
PAINT PINK (-1650 3660);
FORCEPROP 2 LAST CDS_LIB mstr_standard
J 2
(-1650 3650);
DISPLAY 0.787234 (-1650 3650);
PAINT MONO (-1650 3650);
DISPLAY INVISIBLE (-1650 3650);
FORCEPROP 1 LAST BODY_TYPE PLUMBING
J 2
(-1650 3600);
DISPLAY 1.234043 (-1650 3600);
PAINT GREEN (-1650 3600);
DISPLAY INVISIBLE (-1650 3600);
FORCEPROP 1 LAST HDL_TAP TRUE
J 2
(-1975 3525);
DISPLAY 1.234043 (-1975 3525);
PAINT GREEN (-1975 3525);
DISPLAY INVISIBLE (-1975 3525);
FORCEPROP 1 LAST PATH I67
J 2
(-1650 3650);
DISPLAY 0.936170 (-1650 3650);
PAINT GREEN (-1650 3650);
DISPLAY INVISIBLE (-1650 3650);
FORCEADD TAP..6
R 2
(-1650 3550);
FORCEPROP 3 LASTPIN (-1700 3550) SIG_NAME M_F_DQ<39>
J 0
(-1690 3560);
DISPLAY 0.659574 (-1690 3560);
PAINT MONO (-1690 3560);
DISPLAY INVISIBLE (-1690 3560);
FORCEPROP 1 LASTPIN (-1700 3550) BN 39
J 2
(-1650 3560);
DISPLAY 0.617021 (-1650 3560);
PAINT PINK (-1650 3560);
FORCEPROP 2 LAST CDS_LIB mstr_standard
J 2
(-1650 3550);
DISPLAY 0.787234 (-1650 3550);
PAINT MONO (-1650 3550);
DISPLAY INVISIBLE (-1650 3550);
FORCEPROP 1 LAST BODY_TYPE PLUMBING
J 2
(-1650 3500);
DISPLAY 1.234043 (-1650 3500);
PAINT GREEN (-1650 3500);
DISPLAY INVISIBLE (-1650 3500);
FORCEPROP 1 LAST HDL_TAP TRUE
J 2
(-1975 3425);
DISPLAY 1.234043 (-1975 3425);
PAINT GREEN (-1975 3425);
DISPLAY INVISIBLE (-1975 3425);
FORCEPROP 1 LAST PATH I68
J 2
(-1650 3550);
DISPLAY 0.936170 (-1650 3550);
PAINT GREEN (-1650 3550);
DISPLAY INVISIBLE (-1650 3550);
FORCEADD TAP..6
R 2
(-1650 3600);
FORCEPROP 3 LASTPIN (-1700 3600) SIG_NAME M_F_DQ<40>
J 0
(-1690 3610);
DISPLAY 0.659574 (-1690 3610);
PAINT MONO (-1690 3610);
DISPLAY INVISIBLE (-1690 3610);
FORCEPROP 1 LASTPIN (-1700 3600) BN 40
J 2
(-1650 3610);
DISPLAY 0.617021 (-1650 3610);
PAINT PINK (-1650 3610);
FORCEPROP 2 LAST CDS_LIB mstr_standard
J 2
(-1650 3600);
DISPLAY 0.787234 (-1650 3600);
PAINT MONO (-1650 3600);
DISPLAY INVISIBLE (-1650 3600);
FORCEPROP 1 LAST BODY_TYPE PLUMBING
J 2
(-1650 3550);
DISPLAY 1.234043 (-1650 3550);
PAINT GREEN (-1650 3550);
DISPLAY INVISIBLE (-1650 3550);
FORCEPROP 1 LAST HDL_TAP TRUE
J 2
(-1975 3475);
DISPLAY 1.234043 (-1975 3475);
PAINT GREEN (-1975 3475);
DISPLAY INVISIBLE (-1975 3475);
FORCEPROP 1 LAST PATH I69
J 2
(-1650 3600);
DISPLAY 0.936170 (-1650 3600);
PAINT GREEN (-1650 3600);
DISPLAY INVISIBLE (-1650 3600);
FORCEADD TAP..6
R 2
(900 4800);
FORCEPROP 3 LASTPIN (850 4800) SIG_NAME M_F_DQS_DN<14>
J 0
(860 4810);
DISPLAY 0.659574 (860 4810);
PAINT MONO (860 4810);
DISPLAY INVISIBLE (860 4810);
FORCEPROP 1 LASTPIN (850 4800) BN 14
J 2
(900 4810);
DISPLAY 0.617021 (900 4810);
PAINT PINK (900 4810);
FORCEPROP 2 LAST CDS_LIB mstr_standard
J 0
(900 4800);
DISPLAY 0.787234 (900 4800);
PAINT MONO (900 4800);
DISPLAY INVISIBLE (900 4800);
FORCEPROP 1 LAST BODY_TYPE PLUMBING
J 2
(900 4750);
DISPLAY 1.234043 (900 4750);
PAINT GREEN (900 4750);
DISPLAY INVISIBLE (900 4750);
FORCEPROP 1 LAST HDL_TAP TRUE
J 2
(575 4675);
DISPLAY 1.234043 (575 4675);
PAINT GREEN (575 4675);
DISPLAY INVISIBLE (575 4675);
FORCEPROP 1 LAST PATH I7
J 2
(900 4800);
DISPLAY 0.936170 (900 4800);
PAINT GREEN (900 4800);
DISPLAY INVISIBLE (900 4800);
FORCEADD TAP..6
R 2
(-1650 3700);
FORCEPROP 3 LASTPIN (-1700 3700) SIG_NAME M_F_DQ<42>
J 0
(-1690 3710);
DISPLAY 0.659574 (-1690 3710);
PAINT MONO (-1690 3710);
DISPLAY INVISIBLE (-1690 3710);
FORCEPROP 1 LASTPIN (-1700 3700) BN 42
J 2
(-1650 3710);
DISPLAY 0.617021 (-1650 3710);
PAINT PINK (-1650 3710);
FORCEPROP 2 LAST CDS_LIB mstr_standard
J 2
(-1650 3700);
DISPLAY 0.787234 (-1650 3700);
PAINT MONO (-1650 3700);
DISPLAY INVISIBLE (-1650 3700);
FORCEPROP 1 LAST BODY_TYPE PLUMBING
J 2
(-1650 3650);
DISPLAY 1.234043 (-1650 3650);
PAINT GREEN (-1650 3650);
DISPLAY INVISIBLE (-1650 3650);
FORCEPROP 1 LAST HDL_TAP TRUE
J 2
(-1975 3575);
DISPLAY 1.234043 (-1975 3575);
PAINT GREEN (-1975 3575);
DISPLAY INVISIBLE (-1975 3575);
FORCEPROP 1 LAST PATH I70
J 2
(-1650 3700);
DISPLAY 0.936170 (-1650 3700);
PAINT GREEN (-1650 3700);
DISPLAY INVISIBLE (-1650 3700);
FORCEADD TAP..6
R 2
(-1650 3750);
FORCEPROP 3 LASTPIN (-1700 3750) SIG_NAME M_F_DQ<43>
J 0
(-1690 3760);
DISPLAY 0.659574 (-1690 3760);
PAINT MONO (-1690 3760);
DISPLAY INVISIBLE (-1690 3760);
FORCEPROP 1 LASTPIN (-1700 3750) BN 43
J 2
(-1650 3760);
DISPLAY 0.617021 (-1650 3760);
PAINT PINK (-1650 3760);
FORCEPROP 2 LAST CDS_LIB mstr_standard
J 2
(-1650 3750);
DISPLAY 0.787234 (-1650 3750);
PAINT MONO (-1650 3750);
DISPLAY INVISIBLE (-1650 3750);
FORCEPROP 1 LAST BODY_TYPE PLUMBING
J 2
(-1650 3700);
DISPLAY 1.234043 (-1650 3700);
PAINT GREEN (-1650 3700);
DISPLAY INVISIBLE (-1650 3700);
FORCEPROP 1 LAST HDL_TAP TRUE
J 2
(-1975 3625);
DISPLAY 1.234043 (-1975 3625);
PAINT GREEN (-1975 3625);
DISPLAY INVISIBLE (-1975 3625);
FORCEPROP 1 LAST PATH I71
J 2
(-1650 3750);
DISPLAY 0.936170 (-1650 3750);
PAINT GREEN (-1650 3750);
DISPLAY INVISIBLE (-1650 3750);
FORCEADD TAP..6
R 2
(-1650 3350);
FORCEPROP 3 LASTPIN (-1700 3350) SIG_NAME M_F_DQ<35>
J 0
(-1690 3360);
DISPLAY 0.659574 (-1690 3360);
PAINT MONO (-1690 3360);
DISPLAY INVISIBLE (-1690 3360);
FORCEPROP 1 LASTPIN (-1700 3350) BN 35
J 2
(-1650 3360);
DISPLAY 0.617021 (-1650 3360);
PAINT PINK (-1650 3360);
FORCEPROP 2 LAST CDS_LIB mstr_standard
J 2
(-1650 3350);
DISPLAY 0.787234 (-1650 3350);
PAINT MONO (-1650 3350);
DISPLAY INVISIBLE (-1650 3350);
FORCEPROP 1 LAST BODY_TYPE PLUMBING
J 2
(-1650 3300);
DISPLAY 1.234043 (-1650 3300);
PAINT GREEN (-1650 3300);
DISPLAY INVISIBLE (-1650 3300);
FORCEPROP 1 LAST HDL_TAP TRUE
J 2
(-1975 3225);
DISPLAY 1.234043 (-1975 3225);
PAINT GREEN (-1975 3225);
DISPLAY INVISIBLE (-1975 3225);
FORCEPROP 1 LAST PATH I72
J 2
(-1650 3350);
DISPLAY 0.936170 (-1650 3350);
PAINT GREEN (-1650 3350);
DISPLAY INVISIBLE (-1650 3350);
FORCEADD TAP..6
R 2
(-1650 3300);
FORCEPROP 3 LASTPIN (-1700 3300) SIG_NAME M_F_DQ<34>
J 0
(-1690 3310);
DISPLAY 0.659574 (-1690 3310);
PAINT MONO (-1690 3310);
DISPLAY INVISIBLE (-1690 3310);
FORCEPROP 1 LASTPIN (-1700 3300) BN 34
J 2
(-1650 3310);
DISPLAY 0.617021 (-1650 3310);
PAINT PINK (-1650 3310);
FORCEPROP 2 LAST CDS_LIB mstr_standard
J 2
(-1650 3300);
DISPLAY 0.787234 (-1650 3300);
PAINT MONO (-1650 3300);
DISPLAY INVISIBLE (-1650 3300);
FORCEPROP 1 LAST BODY_TYPE PLUMBING
J 2
(-1650 3250);
DISPLAY 1.234043 (-1650 3250);
PAINT GREEN (-1650 3250);
DISPLAY INVISIBLE (-1650 3250);
FORCEPROP 1 LAST HDL_TAP TRUE
J 2
(-1975 3175);
DISPLAY 1.234043 (-1975 3175);
PAINT GREEN (-1975 3175);
DISPLAY INVISIBLE (-1975 3175);
FORCEPROP 1 LAST PATH I73
J 2
(-1650 3300);
DISPLAY 0.936170 (-1650 3300);
PAINT GREEN (-1650 3300);
DISPLAY INVISIBLE (-1650 3300);
FORCEADD TAP..6
R 2
(-1650 3400);
FORCEPROP 3 LASTPIN (-1700 3400) SIG_NAME M_F_DQ<36>
J 0
(-1690 3410);
DISPLAY 0.659574 (-1690 3410);
PAINT MONO (-1690 3410);
DISPLAY INVISIBLE (-1690 3410);
FORCEPROP 1 LASTPIN (-1700 3400) BN 36
J 2
(-1650 3410);
DISPLAY 0.617021 (-1650 3410);
PAINT PINK (-1650 3410);
FORCEPROP 2 LAST CDS_LIB mstr_standard
J 2
(-1650 3400);
DISPLAY 0.787234 (-1650 3400);
PAINT MONO (-1650 3400);
DISPLAY INVISIBLE (-1650 3400);
FORCEPROP 1 LAST BODY_TYPE PLUMBING
J 2
(-1650 3350);
DISPLAY 1.234043 (-1650 3350);
PAINT GREEN (-1650 3350);
DISPLAY INVISIBLE (-1650 3350);
FORCEPROP 1 LAST HDL_TAP TRUE
J 2
(-1975 3275);
DISPLAY 1.234043 (-1975 3275);
PAINT GREEN (-1975 3275);
DISPLAY INVISIBLE (-1975 3275);
FORCEPROP 1 LAST PATH I74
J 2
(-1650 3400);
DISPLAY 0.936170 (-1650 3400);
PAINT GREEN (-1650 3400);
DISPLAY INVISIBLE (-1650 3400);
FORCEADD TAP..6
R 2
(-1650 3450);
FORCEPROP 3 LASTPIN (-1700 3450) SIG_NAME M_F_DQ<37>
J 0
(-1690 3460);
DISPLAY 0.659574 (-1690 3460);
PAINT MONO (-1690 3460);
DISPLAY INVISIBLE (-1690 3460);
FORCEPROP 1 LASTPIN (-1700 3450) BN 37
J 2
(-1650 3460);
DISPLAY 0.617021 (-1650 3460);
PAINT PINK (-1650 3460);
FORCEPROP 2 LAST CDS_LIB mstr_standard
J 2
(-1650 3450);
DISPLAY 0.787234 (-1650 3450);
PAINT MONO (-1650 3450);
DISPLAY INVISIBLE (-1650 3450);
FORCEPROP 1 LAST BODY_TYPE PLUMBING
J 2
(-1650 3400);
DISPLAY 1.234043 (-1650 3400);
PAINT GREEN (-1650 3400);
DISPLAY INVISIBLE (-1650 3400);
FORCEPROP 1 LAST HDL_TAP TRUE
J 2
(-1975 3325);
DISPLAY 1.234043 (-1975 3325);
PAINT GREEN (-1975 3325);
DISPLAY INVISIBLE (-1975 3325);
FORCEPROP 1 LAST PATH I75
J 2
(-1650 3450);
DISPLAY 0.936170 (-1650 3450);
PAINT GREEN (-1650 3450);
DISPLAY INVISIBLE (-1650 3450);
FORCEADD TAP..6
R 2
(-1650 3500);
FORCEPROP 3 LASTPIN (-1700 3500) SIG_NAME M_F_DQ<38>
J 0
(-1690 3510);
DISPLAY 0.659574 (-1690 3510);
PAINT MONO (-1690 3510);
DISPLAY INVISIBLE (-1690 3510);
FORCEPROP 1 LASTPIN (-1700 3500) BN 38
J 2
(-1650 3510);
DISPLAY 0.617021 (-1650 3510);
PAINT PINK (-1650 3510);
FORCEPROP 2 LAST CDS_LIB mstr_standard
J 2
(-1650 3500);
DISPLAY 0.787234 (-1650 3500);
PAINT MONO (-1650 3500);
DISPLAY INVISIBLE (-1650 3500);
FORCEPROP 1 LAST BODY_TYPE PLUMBING
J 2
(-1650 3450);
DISPLAY 1.234043 (-1650 3450);
PAINT GREEN (-1650 3450);
DISPLAY INVISIBLE (-1650 3450);
FORCEPROP 1 LAST HDL_TAP TRUE
J 2
(-1975 3375);
DISPLAY 1.234043 (-1975 3375);
PAINT GREEN (-1975 3375);
DISPLAY INVISIBLE (-1975 3375);
FORCEPROP 1 LAST PATH I76
J 2
(-1650 3500);
DISPLAY 0.936170 (-1650 3500);
PAINT GREEN (-1650 3500);
DISPLAY INVISIBLE (-1650 3500);
FORCEADD TAP..6
R 2
(-1650 3100);
FORCEPROP 3 LASTPIN (-1700 3100) SIG_NAME M_F_DQ<30>
J 0
(-1690 3110);
DISPLAY 0.659574 (-1690 3110);
PAINT MONO (-1690 3110);
DISPLAY INVISIBLE (-1690 3110);
FORCEPROP 1 LASTPIN (-1700 3100) BN 30
J 2
(-1650 3110);
DISPLAY 0.617021 (-1650 3110);
PAINT PINK (-1650 3110);
FORCEPROP 2 LAST CDS_LIB mstr_standard
J 2
(-1650 3100);
DISPLAY 0.787234 (-1650 3100);
PAINT MONO (-1650 3100);
DISPLAY INVISIBLE (-1650 3100);
FORCEPROP 1 LAST BODY_TYPE PLUMBING
J 2
(-1650 3050);
DISPLAY 1.234043 (-1650 3050);
PAINT GREEN (-1650 3050);
DISPLAY INVISIBLE (-1650 3050);
FORCEPROP 1 LAST HDL_TAP TRUE
J 2
(-1975 2975);
DISPLAY 1.234043 (-1975 2975);
PAINT GREEN (-1975 2975);
DISPLAY INVISIBLE (-1975 2975);
FORCEPROP 1 LAST PATH I77
J 2
(-1650 3100);
DISPLAY 0.936170 (-1650 3100);
PAINT GREEN (-1650 3100);
DISPLAY INVISIBLE (-1650 3100);
FORCEADD TAP..6
R 2
(-1650 3150);
FORCEPROP 3 LASTPIN (-1700 3150) SIG_NAME M_F_DQ<31>
J 0
(-1690 3160);
DISPLAY 0.659574 (-1690 3160);
PAINT MONO (-1690 3160);
DISPLAY INVISIBLE (-1690 3160);
FORCEPROP 1 LASTPIN (-1700 3150) BN 31
J 2
(-1650 3160);
DISPLAY 0.617021 (-1650 3160);
PAINT PINK (-1650 3160);
FORCEPROP 2 LAST CDS_LIB mstr_standard
J 2
(-1650 3150);
DISPLAY 0.787234 (-1650 3150);
PAINT MONO (-1650 3150);
DISPLAY INVISIBLE (-1650 3150);
FORCEPROP 1 LAST BODY_TYPE PLUMBING
J 2
(-1650 3100);
DISPLAY 1.234043 (-1650 3100);
PAINT GREEN (-1650 3100);
DISPLAY INVISIBLE (-1650 3100);
FORCEPROP 1 LAST HDL_TAP TRUE
J 2
(-1975 3025);
DISPLAY 1.234043 (-1975 3025);
PAINT GREEN (-1975 3025);
DISPLAY INVISIBLE (-1975 3025);
FORCEPROP 1 LAST PATH I78
J 2
(-1650 3150);
DISPLAY 0.936170 (-1650 3150);
PAINT GREEN (-1650 3150);
DISPLAY INVISIBLE (-1650 3150);
FORCEADD TAP..6
R 2
(-1650 3050);
FORCEPROP 3 LASTPIN (-1700 3050) SIG_NAME M_F_DQ<29>
J 0
(-1690 3060);
DISPLAY 0.659574 (-1690 3060);
PAINT MONO (-1690 3060);
DISPLAY INVISIBLE (-1690 3060);
FORCEPROP 1 LASTPIN (-1700 3050) BN 29
J 2
(-1650 3060);
DISPLAY 0.617021 (-1650 3060);
PAINT PINK (-1650 3060);
FORCEPROP 2 LAST CDS_LIB mstr_standard
J 2
(-1650 3050);
DISPLAY 0.787234 (-1650 3050);
PAINT MONO (-1650 3050);
DISPLAY INVISIBLE (-1650 3050);
FORCEPROP 1 LAST BODY_TYPE PLUMBING
J 2
(-1650 3000);
DISPLAY 1.234043 (-1650 3000);
PAINT GREEN (-1650 3000);
DISPLAY INVISIBLE (-1650 3000);
FORCEPROP 1 LAST HDL_TAP TRUE
J 2
(-1975 2925);
DISPLAY 1.234043 (-1975 2925);
PAINT GREEN (-1975 2925);
DISPLAY INVISIBLE (-1975 2925);
FORCEPROP 1 LAST PATH I79
J 2
(-1650 3050);
DISPLAY 0.936170 (-1650 3050);
PAINT GREEN (-1650 3050);
DISPLAY INVISIBLE (-1650 3050);
FORCEADD TAP..6
R 2
(900 4700);
FORCEPROP 3 LASTPIN (850 4700) SIG_NAME M_F_DQS_DN<13>
J 0
(860 4710);
DISPLAY 0.659574 (860 4710);
PAINT MONO (860 4710);
DISPLAY INVISIBLE (860 4710);
FORCEPROP 1 LASTPIN (850 4700) BN 13
J 2
(900 4710);
DISPLAY 0.617021 (900 4710);
PAINT PINK (900 4710);
FORCEPROP 2 LAST CDS_LIB mstr_standard
J 0
(900 4700);
DISPLAY 0.787234 (900 4700);
PAINT MONO (900 4700);
DISPLAY INVISIBLE (900 4700);
FORCEPROP 1 LAST BODY_TYPE PLUMBING
J 2
(900 4650);
DISPLAY 1.234043 (900 4650);
PAINT GREEN (900 4650);
DISPLAY INVISIBLE (900 4650);
FORCEPROP 1 LAST HDL_TAP TRUE
J 2
(575 4575);
DISPLAY 1.234043 (575 4575);
PAINT GREEN (575 4575);
DISPLAY INVISIBLE (575 4575);
FORCEPROP 1 LAST PATH I8
J 2
(900 4700);
DISPLAY 0.936170 (900 4700);
PAINT GREEN (900 4700);
DISPLAY INVISIBLE (900 4700);
FORCEADD TAP..6
R 2
(-1650 3200);
FORCEPROP 3 LASTPIN (-1700 3200) SIG_NAME M_F_DQ<32>
J 0
(-1690 3210);
DISPLAY 0.659574 (-1690 3210);
PAINT MONO (-1690 3210);
DISPLAY INVISIBLE (-1690 3210);
FORCEPROP 1 LASTPIN (-1700 3200) BN 32
J 2
(-1650 3210);
DISPLAY 0.617021 (-1650 3210);
PAINT PINK (-1650 3210);
FORCEPROP 2 LAST CDS_LIB mstr_standard
J 2
(-1650 3200);
DISPLAY 0.787234 (-1650 3200);
PAINT MONO (-1650 3200);
DISPLAY INVISIBLE (-1650 3200);
FORCEPROP 1 LAST BODY_TYPE PLUMBING
J 2
(-1650 3150);
DISPLAY 1.234043 (-1650 3150);
PAINT GREEN (-1650 3150);
DISPLAY INVISIBLE (-1650 3150);
FORCEPROP 1 LAST HDL_TAP TRUE
J 2
(-1975 3075);
DISPLAY 1.234043 (-1975 3075);
PAINT GREEN (-1975 3075);
DISPLAY INVISIBLE (-1975 3075);
FORCEPROP 1 LAST PATH I80
J 2
(-1650 3200);
DISPLAY 0.936170 (-1650 3200);
PAINT GREEN (-1650 3200);
DISPLAY INVISIBLE (-1650 3200);
FORCEADD TAP..6
R 2
(-1650 3250);
FORCEPROP 3 LASTPIN (-1700 3250) SIG_NAME M_F_DQ<33>
J 0
(-1690 3260);
DISPLAY 0.659574 (-1690 3260);
PAINT MONO (-1690 3260);
DISPLAY INVISIBLE (-1690 3260);
FORCEPROP 1 LASTPIN (-1700 3250) BN 33
J 2
(-1650 3260);
DISPLAY 0.617021 (-1650 3260);
PAINT PINK (-1650 3260);
FORCEPROP 2 LAST CDS_LIB mstr_standard
J 2
(-1650 3250);
DISPLAY 0.787234 (-1650 3250);
PAINT MONO (-1650 3250);
DISPLAY INVISIBLE (-1650 3250);
FORCEPROP 1 LAST BODY_TYPE PLUMBING
J 2
(-1650 3200);
DISPLAY 1.234043 (-1650 3200);
PAINT GREEN (-1650 3200);
DISPLAY INVISIBLE (-1650 3200);
FORCEPROP 1 LAST HDL_TAP TRUE
J 2
(-1975 3125);
DISPLAY 1.234043 (-1975 3125);
PAINT GREEN (-1975 3125);
DISPLAY INVISIBLE (-1975 3125);
FORCEPROP 1 LAST PATH I81
J 2
(-1650 3250);
DISPLAY 0.936170 (-1650 3250);
PAINT GREEN (-1650 3250);
DISPLAY INVISIBLE (-1650 3250);
FORCEADD TAP..6
R 2
(-1650 2850);
FORCEPROP 3 LASTPIN (-1700 2850) SIG_NAME M_F_DQ<25>
J 0
(-1690 2860);
DISPLAY 0.659574 (-1690 2860);
PAINT MONO (-1690 2860);
DISPLAY INVISIBLE (-1690 2860);
FORCEPROP 1 LASTPIN (-1700 2850) BN 25
J 2
(-1650 2860);
DISPLAY 0.617021 (-1650 2860);
PAINT PINK (-1650 2860);
FORCEPROP 2 LAST CDS_LIB mstr_standard
J 2
(-1650 2850);
DISPLAY 0.787234 (-1650 2850);
PAINT MONO (-1650 2850);
DISPLAY INVISIBLE (-1650 2850);
FORCEPROP 1 LAST BODY_TYPE PLUMBING
J 2
(-1650 2800);
DISPLAY 1.234043 (-1650 2800);
PAINT GREEN (-1650 2800);
DISPLAY INVISIBLE (-1650 2800);
FORCEPROP 1 LAST HDL_TAP TRUE
J 2
(-1975 2725);
DISPLAY 1.234043 (-1975 2725);
PAINT GREEN (-1975 2725);
DISPLAY INVISIBLE (-1975 2725);
FORCEPROP 1 LAST PATH I82
J 2
(-1650 2850);
DISPLAY 0.936170 (-1650 2850);
PAINT GREEN (-1650 2850);
DISPLAY INVISIBLE (-1650 2850);
FORCEADD TAP..6
R 2
(-1650 2800);
FORCEPROP 3 LASTPIN (-1700 2800) SIG_NAME M_F_DQ<24>
J 0
(-1690 2810);
DISPLAY 0.659574 (-1690 2810);
PAINT MONO (-1690 2810);
DISPLAY INVISIBLE (-1690 2810);
FORCEPROP 1 LASTPIN (-1700 2800) BN 24
J 2
(-1650 2810);
DISPLAY 0.617021 (-1650 2810);
PAINT PINK (-1650 2810);
FORCEPROP 2 LAST CDS_LIB mstr_standard
J 2
(-1650 2800);
DISPLAY 0.787234 (-1650 2800);
PAINT MONO (-1650 2800);
DISPLAY INVISIBLE (-1650 2800);
FORCEPROP 1 LAST BODY_TYPE PLUMBING
J 2
(-1650 2750);
DISPLAY 1.234043 (-1650 2750);
PAINT GREEN (-1650 2750);
DISPLAY INVISIBLE (-1650 2750);
FORCEPROP 1 LAST HDL_TAP TRUE
J 2
(-1975 2675);
DISPLAY 1.234043 (-1975 2675);
PAINT GREEN (-1975 2675);
DISPLAY INVISIBLE (-1975 2675);
FORCEPROP 1 LAST PATH I83
J 2
(-1650 2800);
DISPLAY 0.936170 (-1650 2800);
PAINT GREEN (-1650 2800);
DISPLAY INVISIBLE (-1650 2800);
FORCEADD TAP..6
R 2
(-1650 2900);
FORCEPROP 3 LASTPIN (-1700 2900) SIG_NAME M_F_DQ<26>
J 0
(-1690 2910);
DISPLAY 0.659574 (-1690 2910);
PAINT MONO (-1690 2910);
DISPLAY INVISIBLE (-1690 2910);
FORCEPROP 1 LASTPIN (-1700 2900) BN 26
J 2
(-1650 2910);
DISPLAY 0.617021 (-1650 2910);
PAINT PINK (-1650 2910);
FORCEPROP 2 LAST CDS_LIB mstr_standard
J 2
(-1650 2900);
DISPLAY 0.787234 (-1650 2900);
PAINT MONO (-1650 2900);
DISPLAY INVISIBLE (-1650 2900);
FORCEPROP 1 LAST BODY_TYPE PLUMBING
J 2
(-1650 2850);
DISPLAY 1.234043 (-1650 2850);
PAINT GREEN (-1650 2850);
DISPLAY INVISIBLE (-1650 2850);
FORCEPROP 1 LAST HDL_TAP TRUE
J 2
(-1975 2775);
DISPLAY 1.234043 (-1975 2775);
PAINT GREEN (-1975 2775);
DISPLAY INVISIBLE (-1975 2775);
FORCEPROP 1 LAST PATH I84
J 2
(-1650 2900);
DISPLAY 0.936170 (-1650 2900);
PAINT GREEN (-1650 2900);
DISPLAY INVISIBLE (-1650 2900);
FORCEADD TAP..6
R 2
(-1650 3000);
FORCEPROP 3 LASTPIN (-1700 3000) SIG_NAME M_F_DQ<28>
J 0
(-1690 3010);
DISPLAY 0.659574 (-1690 3010);
PAINT MONO (-1690 3010);
DISPLAY INVISIBLE (-1690 3010);
FORCEPROP 1 LASTPIN (-1700 3000) BN 28
J 2
(-1650 3010);
DISPLAY 0.617021 (-1650 3010);
PAINT PINK (-1650 3010);
FORCEPROP 2 LAST CDS_LIB mstr_standard
J 2
(-1650 3000);
DISPLAY 0.787234 (-1650 3000);
PAINT MONO (-1650 3000);
DISPLAY INVISIBLE (-1650 3000);
FORCEPROP 1 LAST BODY_TYPE PLUMBING
J 2
(-1650 2950);
DISPLAY 1.234043 (-1650 2950);
PAINT GREEN (-1650 2950);
DISPLAY INVISIBLE (-1650 2950);
FORCEPROP 1 LAST HDL_TAP TRUE
J 2
(-1975 2875);
DISPLAY 1.234043 (-1975 2875);
PAINT GREEN (-1975 2875);
DISPLAY INVISIBLE (-1975 2875);
FORCEPROP 1 LAST PATH I85
J 2
(-1650 3000);
DISPLAY 0.936170 (-1650 3000);
PAINT GREEN (-1650 3000);
DISPLAY INVISIBLE (-1650 3000);
FORCEADD TAP..6
R 2
(-1650 2950);
FORCEPROP 3 LASTPIN (-1700 2950) SIG_NAME M_F_DQ<27>
J 0
(-1690 2960);
DISPLAY 0.659574 (-1690 2960);
PAINT MONO (-1690 2960);
DISPLAY INVISIBLE (-1690 2960);
FORCEPROP 1 LASTPIN (-1700 2950) BN 27
J 2
(-1650 2960);
DISPLAY 0.617021 (-1650 2960);
PAINT PINK (-1650 2960);
FORCEPROP 2 LAST CDS_LIB mstr_standard
J 2
(-1650 2950);
DISPLAY 0.787234 (-1650 2950);
PAINT MONO (-1650 2950);
DISPLAY INVISIBLE (-1650 2950);
FORCEPROP 1 LAST BODY_TYPE PLUMBING
J 2
(-1650 2900);
DISPLAY 1.234043 (-1650 2900);
PAINT GREEN (-1650 2900);
DISPLAY INVISIBLE (-1650 2900);
FORCEPROP 1 LAST HDL_TAP TRUE
J 2
(-1975 2825);
DISPLAY 1.234043 (-1975 2825);
PAINT GREEN (-1975 2825);
DISPLAY INVISIBLE (-1975 2825);
FORCEPROP 1 LAST PATH I86
J 2
(-1650 2950);
DISPLAY 0.936170 (-1650 2950);
PAINT GREEN (-1650 2950);
DISPLAY INVISIBLE (-1650 2950);
FORCEADD TAP..6
R 2
(-1650 2550);
FORCEPROP 3 LASTPIN (-1700 2550) SIG_NAME M_F_DQ<19>
J 0
(-1690 2560);
DISPLAY 0.659574 (-1690 2560);
PAINT MONO (-1690 2560);
DISPLAY INVISIBLE (-1690 2560);
FORCEPROP 1 LASTPIN (-1700 2550) BN 19
J 2
(-1650 2560);
DISPLAY 0.617021 (-1650 2560);
PAINT PINK (-1650 2560);
FORCEPROP 2 LAST CDS_LIB mstr_standard
J 2
(-1650 2550);
DISPLAY 0.787234 (-1650 2550);
PAINT MONO (-1650 2550);
DISPLAY INVISIBLE (-1650 2550);
FORCEPROP 1 LAST BODY_TYPE PLUMBING
J 2
(-1650 2500);
DISPLAY 1.234043 (-1650 2500);
PAINT GREEN (-1650 2500);
DISPLAY INVISIBLE (-1650 2500);
FORCEPROP 1 LAST HDL_TAP TRUE
J 2
(-1975 2425);
DISPLAY 1.234043 (-1975 2425);
PAINT GREEN (-1975 2425);
DISPLAY INVISIBLE (-1975 2425);
FORCEPROP 1 LAST PATH I87
J 2
(-1650 2550);
DISPLAY 0.936170 (-1650 2550);
PAINT GREEN (-1650 2550);
DISPLAY INVISIBLE (-1650 2550);
FORCEADD TAP..6
R 2
(-1650 2600);
FORCEPROP 3 LASTPIN (-1700 2600) SIG_NAME M_F_DQ<20>
J 0
(-1690 2610);
DISPLAY 0.659574 (-1690 2610);
PAINT MONO (-1690 2610);
DISPLAY INVISIBLE (-1690 2610);
FORCEPROP 1 LASTPIN (-1700 2600) BN 20
J 2
(-1650 2610);
DISPLAY 0.617021 (-1650 2610);
PAINT PINK (-1650 2610);
FORCEPROP 2 LAST CDS_LIB mstr_standard
J 2
(-1650 2600);
DISPLAY 0.787234 (-1650 2600);
PAINT MONO (-1650 2600);
DISPLAY INVISIBLE (-1650 2600);
FORCEPROP 1 LAST BODY_TYPE PLUMBING
J 2
(-1650 2550);
DISPLAY 1.234043 (-1650 2550);
PAINT GREEN (-1650 2550);
DISPLAY INVISIBLE (-1650 2550);
FORCEPROP 1 LAST HDL_TAP TRUE
J 2
(-1975 2475);
DISPLAY 1.234043 (-1975 2475);
PAINT GREEN (-1975 2475);
DISPLAY INVISIBLE (-1975 2475);
FORCEPROP 1 LAST PATH I88
J 2
(-1650 2600);
DISPLAY 0.936170 (-1650 2600);
PAINT GREEN (-1650 2600);
DISPLAY INVISIBLE (-1650 2600);
FORCEADD TAP..6
R 2
(-1650 2650);
FORCEPROP 3 LASTPIN (-1700 2650) SIG_NAME M_F_DQ<21>
J 0
(-1690 2660);
DISPLAY 0.659574 (-1690 2660);
PAINT MONO (-1690 2660);
DISPLAY INVISIBLE (-1690 2660);
FORCEPROP 1 LASTPIN (-1700 2650) BN 21
J 2
(-1650 2660);
DISPLAY 0.617021 (-1650 2660);
PAINT PINK (-1650 2660);
FORCEPROP 2 LAST CDS_LIB mstr_standard
J 2
(-1650 2650);
DISPLAY 0.787234 (-1650 2650);
PAINT MONO (-1650 2650);
DISPLAY INVISIBLE (-1650 2650);
FORCEPROP 1 LAST BODY_TYPE PLUMBING
J 2
(-1650 2600);
DISPLAY 1.234043 (-1650 2600);
PAINT GREEN (-1650 2600);
DISPLAY INVISIBLE (-1650 2600);
FORCEPROP 1 LAST HDL_TAP TRUE
J 2
(-1975 2525);
DISPLAY 1.234043 (-1975 2525);
PAINT GREEN (-1975 2525);
DISPLAY INVISIBLE (-1975 2525);
FORCEPROP 1 LAST PATH I89
J 2
(-1650 2650);
DISPLAY 0.936170 (-1650 2650);
PAINT GREEN (-1650 2650);
DISPLAY INVISIBLE (-1650 2650);
FORCEADD TAP..6
R 2
(900 4600);
FORCEPROP 3 LASTPIN (850 4600) SIG_NAME M_F_DQS_DN<12>
J 0
(860 4610);
DISPLAY 0.659574 (860 4610);
PAINT MONO (860 4610);
DISPLAY INVISIBLE (860 4610);
FORCEPROP 1 LASTPIN (850 4600) BN 12
J 2
(900 4610);
DISPLAY 0.617021 (900 4610);
PAINT PINK (900 4610);
FORCEPROP 2 LAST CDS_LIB mstr_standard
J 0
(900 4600);
DISPLAY 0.787234 (900 4600);
PAINT MONO (900 4600);
DISPLAY INVISIBLE (900 4600);
FORCEPROP 1 LAST BODY_TYPE PLUMBING
J 2
(900 4550);
DISPLAY 1.234043 (900 4550);
PAINT GREEN (900 4550);
DISPLAY INVISIBLE (900 4550);
FORCEPROP 1 LAST HDL_TAP TRUE
J 2
(575 4475);
DISPLAY 1.234043 (575 4475);
PAINT GREEN (575 4475);
DISPLAY INVISIBLE (575 4475);
FORCEPROP 1 LAST PATH I9
J 2
(900 4600);
DISPLAY 0.936170 (900 4600);
PAINT GREEN (900 4600);
DISPLAY INVISIBLE (900 4600);
FORCEADD TAP..6
R 2
(-1650 2750);
FORCEPROP 3 LASTPIN (-1700 2750) SIG_NAME M_F_DQ<23>
J 0
(-1690 2760);
DISPLAY 0.659574 (-1690 2760);
PAINT MONO (-1690 2760);
DISPLAY INVISIBLE (-1690 2760);
FORCEPROP 1 LASTPIN (-1700 2750) BN 23
J 2
(-1650 2760);
DISPLAY 0.617021 (-1650 2760);
PAINT PINK (-1650 2760);
FORCEPROP 2 LAST CDS_LIB mstr_standard
J 2
(-1650 2750);
DISPLAY 0.787234 (-1650 2750);
PAINT MONO (-1650 2750);
DISPLAY INVISIBLE (-1650 2750);
FORCEPROP 1 LAST BODY_TYPE PLUMBING
J 2
(-1650 2700);
DISPLAY 1.234043 (-1650 2700);
PAINT GREEN (-1650 2700);
DISPLAY INVISIBLE (-1650 2700);
FORCEPROP 1 LAST HDL_TAP TRUE
J 2
(-1975 2625);
DISPLAY 1.234043 (-1975 2625);
PAINT GREEN (-1975 2625);
DISPLAY INVISIBLE (-1975 2625);
FORCEPROP 1 LAST PATH I90
J 2
(-1650 2750);
DISPLAY 0.936170 (-1650 2750);
PAINT GREEN (-1650 2750);
DISPLAY INVISIBLE (-1650 2750);
FORCEADD TAP..6
R 2
(-1650 2700);
FORCEPROP 3 LASTPIN (-1700 2700) SIG_NAME M_F_DQ<22>
J 0
(-1690 2710);
DISPLAY 0.659574 (-1690 2710);
PAINT MONO (-1690 2710);
DISPLAY INVISIBLE (-1690 2710);
FORCEPROP 1 LASTPIN (-1700 2700) BN 22
J 2
(-1650 2710);
DISPLAY 0.617021 (-1650 2710);
PAINT PINK (-1650 2710);
FORCEPROP 2 LAST CDS_LIB mstr_standard
J 2
(-1650 2700);
DISPLAY 0.787234 (-1650 2700);
PAINT MONO (-1650 2700);
DISPLAY INVISIBLE (-1650 2700);
FORCEPROP 1 LAST BODY_TYPE PLUMBING
J 2
(-1650 2650);
DISPLAY 1.234043 (-1650 2650);
PAINT GREEN (-1650 2650);
DISPLAY INVISIBLE (-1650 2650);
FORCEPROP 1 LAST HDL_TAP TRUE
J 2
(-1975 2575);
DISPLAY 1.234043 (-1975 2575);
PAINT GREEN (-1975 2575);
DISPLAY INVISIBLE (-1975 2575);
FORCEPROP 1 LAST PATH I91
J 2
(-1650 2700);
DISPLAY 0.936170 (-1650 2700);
PAINT GREEN (-1650 2700);
DISPLAY INVISIBLE (-1650 2700);
FORCEADD TAP..6
R 2
(-1650 2300);
FORCEPROP 3 LASTPIN (-1700 2300) SIG_NAME M_F_DQ<14>
J 0
(-1690 2310);
DISPLAY 0.659574 (-1690 2310);
PAINT MONO (-1690 2310);
DISPLAY INVISIBLE (-1690 2310);
FORCEPROP 1 LASTPIN (-1700 2300) BN 14
J 2
(-1650 2310);
DISPLAY 0.617021 (-1650 2310);
PAINT PINK (-1650 2310);
FORCEPROP 2 LAST CDS_LIB mstr_standard
J 2
(-1650 2300);
DISPLAY 0.787234 (-1650 2300);
PAINT MONO (-1650 2300);
DISPLAY INVISIBLE (-1650 2300);
FORCEPROP 1 LAST BODY_TYPE PLUMBING
J 2
(-1650 2250);
DISPLAY 1.234043 (-1650 2250);
PAINT GREEN (-1650 2250);
DISPLAY INVISIBLE (-1650 2250);
FORCEPROP 1 LAST HDL_TAP TRUE
J 2
(-1975 2175);
DISPLAY 1.234043 (-1975 2175);
PAINT GREEN (-1975 2175);
DISPLAY INVISIBLE (-1975 2175);
FORCEPROP 1 LAST PATH I92
J 2
(-1650 2300);
DISPLAY 0.936170 (-1650 2300);
PAINT GREEN (-1650 2300);
DISPLAY INVISIBLE (-1650 2300);
FORCEADD TAP..6
R 2
(-1650 2350);
FORCEPROP 3 LASTPIN (-1700 2350) SIG_NAME M_F_DQ<15>
J 0
(-1690 2360);
DISPLAY 0.659574 (-1690 2360);
PAINT MONO (-1690 2360);
DISPLAY INVISIBLE (-1690 2360);
FORCEPROP 1 LASTPIN (-1700 2350) BN 15
J 2
(-1650 2360);
DISPLAY 0.617021 (-1650 2360);
PAINT PINK (-1650 2360);
FORCEPROP 2 LAST CDS_LIB mstr_standard
J 2
(-1650 2350);
DISPLAY 0.787234 (-1650 2350);
PAINT MONO (-1650 2350);
DISPLAY INVISIBLE (-1650 2350);
FORCEPROP 1 LAST BODY_TYPE PLUMBING
J 2
(-1650 2300);
DISPLAY 1.234043 (-1650 2300);
PAINT GREEN (-1650 2300);
DISPLAY INVISIBLE (-1650 2300);
FORCEPROP 1 LAST HDL_TAP TRUE
J 2
(-1975 2225);
DISPLAY 1.234043 (-1975 2225);
PAINT GREEN (-1975 2225);
DISPLAY INVISIBLE (-1975 2225);
FORCEPROP 1 LAST PATH I93
J 2
(-1650 2350);
DISPLAY 0.936170 (-1650 2350);
PAINT GREEN (-1650 2350);
DISPLAY INVISIBLE (-1650 2350);
FORCEADD TAP..6
R 2
(-1650 2450);
FORCEPROP 3 LASTPIN (-1700 2450) SIG_NAME M_F_DQ<17>
J 0
(-1690 2460);
DISPLAY 0.659574 (-1690 2460);
PAINT MONO (-1690 2460);
DISPLAY INVISIBLE (-1690 2460);
FORCEPROP 1 LASTPIN (-1700 2450) BN 17
J 2
(-1650 2460);
DISPLAY 0.617021 (-1650 2460);
PAINT PINK (-1650 2460);
FORCEPROP 2 LAST CDS_LIB mstr_standard
J 2
(-1650 2450);
DISPLAY 0.787234 (-1650 2450);
PAINT MONO (-1650 2450);
DISPLAY INVISIBLE (-1650 2450);
FORCEPROP 1 LAST BODY_TYPE PLUMBING
J 2
(-1650 2400);
DISPLAY 1.234043 (-1650 2400);
PAINT GREEN (-1650 2400);
DISPLAY INVISIBLE (-1650 2400);
FORCEPROP 1 LAST HDL_TAP TRUE
J 2
(-1975 2325);
DISPLAY 1.234043 (-1975 2325);
PAINT GREEN (-1975 2325);
DISPLAY INVISIBLE (-1975 2325);
FORCEPROP 1 LAST PATH I94
J 2
(-1650 2450);
DISPLAY 0.936170 (-1650 2450);
PAINT GREEN (-1650 2450);
DISPLAY INVISIBLE (-1650 2450);
FORCEADD TAP..6
R 2
(-1650 2400);
FORCEPROP 3 LASTPIN (-1700 2400) SIG_NAME M_F_DQ<16>
J 0
(-1690 2410);
DISPLAY 0.659574 (-1690 2410);
PAINT MONO (-1690 2410);
DISPLAY INVISIBLE (-1690 2410);
FORCEPROP 1 LASTPIN (-1700 2400) BN 16
J 2
(-1650 2410);
DISPLAY 0.617021 (-1650 2410);
PAINT PINK (-1650 2410);
FORCEPROP 2 LAST CDS_LIB mstr_standard
J 2
(-1650 2400);
DISPLAY 0.787234 (-1650 2400);
PAINT MONO (-1650 2400);
DISPLAY INVISIBLE (-1650 2400);
FORCEPROP 1 LAST BODY_TYPE PLUMBING
J 2
(-1650 2350);
DISPLAY 1.234043 (-1650 2350);
PAINT GREEN (-1650 2350);
DISPLAY INVISIBLE (-1650 2350);
FORCEPROP 1 LAST HDL_TAP TRUE
J 2
(-1975 2275);
DISPLAY 1.234043 (-1975 2275);
PAINT GREEN (-1975 2275);
DISPLAY INVISIBLE (-1975 2275);
FORCEPROP 1 LAST PATH I95
J 2
(-1650 2400);
DISPLAY 0.936170 (-1650 2400);
PAINT GREEN (-1650 2400);
DISPLAY INVISIBLE (-1650 2400);
FORCEADD TAP..6
R 2
(-1650 2500);
FORCEPROP 3 LASTPIN (-1700 2500) SIG_NAME M_F_DQ<18>
J 0
(-1690 2510);
DISPLAY 0.659574 (-1690 2510);
PAINT MONO (-1690 2510);
DISPLAY INVISIBLE (-1690 2510);
FORCEPROP 1 LASTPIN (-1700 2500) BN 18
J 2
(-1650 2510);
DISPLAY 0.617021 (-1650 2510);
PAINT PINK (-1650 2510);
FORCEPROP 2 LAST CDS_LIB mstr_standard
J 2
(-1650 2500);
DISPLAY 0.787234 (-1650 2500);
PAINT MONO (-1650 2500);
DISPLAY INVISIBLE (-1650 2500);
FORCEPROP 1 LAST BODY_TYPE PLUMBING
J 2
(-1650 2450);
DISPLAY 1.234043 (-1650 2450);
PAINT GREEN (-1650 2450);
DISPLAY INVISIBLE (-1650 2450);
FORCEPROP 1 LAST HDL_TAP TRUE
J 2
(-1975 2375);
DISPLAY 1.234043 (-1975 2375);
PAINT GREEN (-1975 2375);
DISPLAY INVISIBLE (-1975 2375);
FORCEPROP 1 LAST PATH I96
J 2
(-1650 2500);
DISPLAY 0.936170 (-1650 2500);
PAINT GREEN (-1650 2500);
DISPLAY INVISIBLE (-1650 2500);
FORCEADD TAP..6
R 2
(-1650 2250);
FORCEPROP 3 LASTPIN (-1700 2250) SIG_NAME M_F_DQ<13>
J 0
(-1690 2260);
DISPLAY 0.659574 (-1690 2260);
PAINT MONO (-1690 2260);
DISPLAY INVISIBLE (-1690 2260);
FORCEPROP 1 LASTPIN (-1700 2250) BN 13
J 2
(-1650 2260);
DISPLAY 0.617021 (-1650 2260);
PAINT PINK (-1650 2260);
FORCEPROP 2 LAST CDS_LIB mstr_standard
J 2
(-1650 2250);
DISPLAY 0.787234 (-1650 2250);
PAINT MONO (-1650 2250);
DISPLAY INVISIBLE (-1650 2250);
FORCEPROP 1 LAST BODY_TYPE PLUMBING
J 2
(-1650 2200);
DISPLAY 1.234043 (-1650 2200);
PAINT GREEN (-1650 2200);
DISPLAY INVISIBLE (-1650 2200);
FORCEPROP 1 LAST HDL_TAP TRUE
J 2
(-1975 2125);
DISPLAY 1.234043 (-1975 2125);
PAINT GREEN (-1975 2125);
DISPLAY INVISIBLE (-1975 2125);
FORCEPROP 1 LAST PATH I97
J 2
(-1650 2250);
DISPLAY 0.936170 (-1650 2250);
PAINT GREEN (-1650 2250);
DISPLAY INVISIBLE (-1650 2250);
FORCEADD TAP..6
R 2
(-1650 2150);
FORCEPROP 3 LASTPIN (-1700 2150) SIG_NAME M_F_DQ<11>
J 0
(-1690 2160);
DISPLAY 0.659574 (-1690 2160);
PAINT MONO (-1690 2160);
DISPLAY INVISIBLE (-1690 2160);
FORCEPROP 1 LASTPIN (-1700 2150) BN 11
J 2
(-1650 2160);
DISPLAY 0.617021 (-1650 2160);
PAINT PINK (-1650 2160);
FORCEPROP 2 LAST CDS_LIB mstr_standard
J 2
(-1650 2150);
DISPLAY 0.787234 (-1650 2150);
PAINT MONO (-1650 2150);
DISPLAY INVISIBLE (-1650 2150);
FORCEPROP 1 LAST BODY_TYPE PLUMBING
J 2
(-1650 2100);
DISPLAY 1.234043 (-1650 2100);
PAINT GREEN (-1650 2100);
DISPLAY INVISIBLE (-1650 2100);
FORCEPROP 1 LAST HDL_TAP TRUE
J 2
(-1975 2025);
DISPLAY 1.234043 (-1975 2025);
PAINT GREEN (-1975 2025);
DISPLAY INVISIBLE (-1975 2025);
FORCEPROP 1 LAST PATH I98
J 2
(-1650 2150);
DISPLAY 0.936170 (-1650 2150);
PAINT GREEN (-1650 2150);
DISPLAY INVISIBLE (-1650 2150);
FORCEADD TAP..6
R 2
(-1650 2200);
FORCEPROP 3 LASTPIN (-1700 2200) SIG_NAME M_F_DQ<12>
J 0
(-1690 2210);
DISPLAY 0.659574 (-1690 2210);
PAINT MONO (-1690 2210);
DISPLAY INVISIBLE (-1690 2210);
FORCEPROP 1 LASTPIN (-1700 2200) BN 12
J 2
(-1650 2210);
DISPLAY 0.617021 (-1650 2210);
PAINT PINK (-1650 2210);
FORCEPROP 2 LAST CDS_LIB mstr_standard
J 2
(-1650 2200);
DISPLAY 0.787234 (-1650 2200);
PAINT MONO (-1650 2200);
DISPLAY INVISIBLE (-1650 2200);
FORCEPROP 1 LAST BODY_TYPE PLUMBING
J 2
(-1650 2150);
DISPLAY 1.234043 (-1650 2150);
PAINT GREEN (-1650 2150);
DISPLAY INVISIBLE (-1650 2150);
FORCEPROP 1 LAST HDL_TAP TRUE
J 2
(-1975 2075);
DISPLAY 1.234043 (-1975 2075);
PAINT GREEN (-1975 2075);
DISPLAY INVISIBLE (-1975 2075);
FORCEPROP 1 LAST PATH I99
J 2
(-1650 2200);
DISPLAY 0.936170 (-1650 2200);
PAINT GREEN (-1650 2200);
DISPLAY INVISIBLE (-1650 2200);
FORCEADD BOM_NOTE..1
(-5025 5250);
FORCEPROP 0 LAST L1 UNSTUFF FOR SKU B
J 0
(-5175 5150);
DISPLAY 1.063830 (-5175 5150);
PAINT WHITE (-5175 5150);
FORCEPROP 2 LAST BOM_COST SB
J 0
(-5175 5225);
DISPLAY 1.361702 (-5175 5225);
PAINT ORANGE (-5175 5225);
DISPLAY INVISIBLE (-5175 5225);
FORCEPROP 2 LAST CDS_LIB mstr_symbols
J 0
(-5025 5250);
PAINT ORANGE (-5025 5250);
DISPLAY INVISIBLE (-5025 5250);
FORCEPROP 1 LAST COMMENT_BODY TRUE
J 0
(-5000 5350);
DISPLAY 1.319149 (-5000 5350);
PAINT ORANGE (-5000 5350);
DISPLAY INVISIBLE (-5000 5350);
FORCEPROP 2 LAST ROOM SB_HEADERS
J 0
(-5175 5225);
DISPLAY 1.361702 (-5175 5225);
PAINT ORANGE (-5175 5225);
DISPLAY INVISIBLE (-5175 5225);
FORCEADD INTEL_CORP_BPAGE..1
(2650 500);
FORCEPROP 1 LAST CDS_CON_LAST_MODIFIED Tue Dec 01 11:51:32 2015
J 0
(1225 825);
DISPLAY 0.787234 (1225 825);
PAINT ORANGE (1225 825);
DISPLAY INVISIBLE (1225 825);
FORCEPROP 1 LAST CUSTOM_TXT_CDS <CURRENT_DESIGN_SHEET> OF <TOTAL_DESIGN_SHEETS>
J 0
(2150 525);
PAINT GREEN (2150 525);
FORCEPROP 1 LAST CUSTOM_TXT_CDS <CON_LAST_MODIFIED>
J 0
(725 850);
PAINT GREEN (725 850);
FORCEPROP 2 LAST CUSTOM_TXT_CDS <XR_PAGE_TITLE>
J 0
(-5240 5750);
DISPLAY 0.638298 (-5240 5750);
PAINT PINK (-5240 5750);
DISPLAY INVISIBLE (-5240 5750);
FORCEPROP 1 LAST SCH_ADDRESS3 Santa Clara, CA 95052-8119
J 0
(-1325 525);
DISPLAY 0.617021 (-1325 525);
PAINT GREEN (-1325 525);
FORCEPROP 1 LAST SCH_ADDRESS2 P.O. BOX 58119
J 0
(-1325 575);
DISPLAY 0.617021 (-1325 575);
PAINT GREEN (-1325 575);
FORCEPROP 1 LAST SCH_ADDRESS1 2200 Mission College Blvd.
J 0
(-1325 625);
DISPLAY 0.617021 (-1325 625);
PAINT GREEN (-1325 625);
FORCEPROP 1 LAST SCH_TITLE CPU0 DDR4 CH F DIMM1
J 0
(-5300 550);
DISPLAY 1.212766 (-5300 550);
PAINT WHITE (-5300 550);
FORCEPROP 1 LAST SCH_NUMBER H4694802
J 0
(1350 650);
DISPLAY 1.212766 (1350 650);
PAINT YELLOW (1350 650);
FORCEPROP 1 LAST SCH_DEPT BESD
J 1
(-1800 600);
DISPLAY 1.212766 (-1800 600);
PAINT YELLOW (-1800 600);
FORCEPROP 1 LAST SCH_REV 2.420
J 0
(2400 650);
DISPLAY 0.978723 (2400 650);
PAINT YELLOW (2400 650);
FORCEPROP 2 LAST PAGE_BORDER TRUE
J 0
(-5240 5750);
DISPLAY 0.680851 (-5240 5750);
PAINT PINK (-5240 5750);
DISPLAY INVISIBLE (-5240 5750);
FORCEPROP 2 LAST CDS_LIB mstr_symbols
J 0
(2650 500);
DISPLAY 0.787234 (2650 500);
PAINT MONO (2650 500);
DISPLAY INVISIBLE (2650 500);
FORCEPROP 1 LAST COMMENT_BODY TRUE
J 0
(2660 510);
DISPLAY 0.382979 (2660 510);
PAINT GREEN (2660 510);
DISPLAY INVISIBLE (2660 510);
FORCEPROP 2 LAST CDS_XR_PAGE_TITLE CR-54 : @BASEBOARD_FAB2_LIB.BASEBOARD_FAB2(SCH_1):PAGE54
J 0
(-5240 5750);
DISPLAY 0.638298 (-5240 5750);
PAINT PINK (-5240 5750);
DISPLAY INVISIBLE (-5240 5750);
WIRE 17 -1 (750 5175)(750 5200);
WIRE 17 -1 (750 5075)(750 5175);
WIRE 17 -1 (1525 5200)(750 5200);
FORCEPROP 2 LAST SIG_NAME M_F_DQS_DP<17:0>
J 0
(1000 5210);
DISPLAY 0.617021 (1000 5210);
PAINT ORANGE (1000 5210);
WIRE 17 -1 (750 4375)(750 4475);
WIRE 17 -1 (750 4275)(750 4375);
WIRE 17 -1 (750 4475)(750 4575);
WIRE 17 -1 (750 4575)(750 4675);
WIRE 17 -1 (750 4175)(750 4275);
WIRE 17 -1 (750 4075)(750 4175);
WIRE 17 -1 (750 4675)(750 4775);
WIRE 17 -1 (750 4775)(750 4875);
WIRE 17 -1 (750 3975)(750 4075);
WIRE 17 -1 (750 3875)(750 3975);
WIRE 17 -1 (750 4875)(750 4975);
WIRE 17 -1 (750 4975)(750 5075);
WIRE 17 -1 (750 3775)(750 3875);
WIRE 17 -1 (750 3675)(750 3775);
WIRE 17 -1 (750 3575)(750 3675);
WIRE 17 -1 (750 3475)(750 3575);
WIRE 17 -1 (950 4325)(950 4425);
WIRE 17 -1 (950 4225)(950 4325);
WIRE 17 -1 (950 4425)(950 4525);
WIRE 17 -1 (950 4525)(950 4625);
WIRE 17 -1 (950 4125)(950 4225);
WIRE 17 -1 (950 4025)(950 4125);
WIRE 17 -1 (950 4625)(950 4725);
WIRE 17 -1 (950 4725)(950 4825);
WIRE 17 -1 (950 3925)(950 4025);
WIRE 17 -1 (950 3825)(950 3925);
WIRE 17 -1 (950 4825)(950 4925);
WIRE 17 -1 (950 4925)(950 5025);
WIRE 17 -1 (950 3725)(950 3825);
WIRE 17 -1 (950 3625)(950 3725);
WIRE 17 -1 (950 5025)(950 5125);
WIRE 17 -1 (950 5125)(950 5150);
WIRE 17 -1 (950 3525)(950 3625);
WIRE 17 -1 (950 3425)(950 3525);
WIRE 17 -1 (1525 5150)(950 5150);
FORCEPROP 2 LAST SIG_NAME M_F_DQS_DN<17:0>
J 0
(1000 5160);
DISPLAY 0.617021 (1000 5160);
PAINT ORANGE (1000 5160);
WIRE 17 -1 (-1600 4625)(-1600 4675);
WIRE 17 -1 (-1600 4575)(-1600 4625);
WIRE 17 -1 (-1600 4675)(-1600 4725);
WIRE 17 -1 (-1600 4725)(-1600 4775);
WIRE 17 -1 (-1600 4525)(-1600 4575);
WIRE 17 -1 (-1600 4475)(-1600 4525);
WIRE 17 -1 (-1600 4775)(-1600 4800);
WIRE 17 -1 (-1150 4800)(-1600 4800);
FORCEPROP 2 LAST SIG_NAME M_F_DQ<63:0>
J 0
(-1560 4810);
DISPLAY 0.617021 (-1560 4810);
PAINT ORANGE (-1560 4810);
WIRE 17 -1 (-1600 4125)(-1600 4175);
WIRE 17 -1 (-1600 4075)(-1600 4125);
WIRE 17 -1 (-1600 4175)(-1600 4225);
WIRE 17 -1 (-1600 4225)(-1600 4275);
WIRE 17 -1 (-1600 4025)(-1600 4075);
WIRE 17 -1 (-1600 3975)(-1600 4025);
WIRE 17 -1 (-1600 4275)(-1600 4325);
WIRE 17 -1 (-1600 4325)(-1600 4375);
WIRE 17 -1 (-1600 3925)(-1600 3975);
WIRE 17 -1 (-1600 3875)(-1600 3925);
WIRE 17 -1 (-1600 4375)(-1600 4425);
WIRE 17 -1 (-1600 4425)(-1600 4475);
WIRE 17 -1 (-1600 3825)(-1600 3875);
WIRE 17 -1 (-1600 3775)(-1600 3825);
WIRE 17 -1 (-1600 3725)(-1600 3775);
WIRE 17 -1 (-1600 3675)(-1600 3725);
WIRE 17 -1 (-1600 3625)(-1600 3675);
WIRE 17 -1 (-1600 3575)(-1600 3625);
WIRE 17 -1 (-1600 3525)(-1600 3575);
WIRE 17 -1 (-1600 3475)(-1600 3525);
WIRE 17 -1 (-3200 4675)(-3200 4725);
WIRE 17 -1 (-3200 4625)(-3200 4675);
WIRE 17 -1 (-3200 4725)(-3200 4775);
WIRE 17 -1 (-3200 4775)(-3200 4800);
WIRE 17 -1 (-3200 4575)(-3200 4625);
WIRE 17 -1 (-3200 4525)(-3200 4575);
WIRE 17 -1 (-3725 4800)(-3200 4800);
FORCEPROP 2 LAST SIG_NAME M_F_MA<17:0>
J 0
(-3675 4810);
DISPLAY 0.617021 (-3675 4810);
PAINT ORANGE (-3675 4810);
WIRE 17 -1 (-3200 4475)(-3200 4525);
WIRE 17 -1 (-3200 4425)(-3200 4475);
WIRE 17 -1 (-3200 4375)(-3200 4425);
WIRE 17 -1 (-3200 4325)(-3200 4375);
WIRE 17 -1 (-3200 4275)(-3200 4325);
WIRE 17 -1 (-3200 4225)(-3200 4275);
WIRE 17 -1 (-3200 4175)(-3200 4225);
WIRE 17 -1 (-3200 4125)(-3200 4175);
WIRE 17 -1 (-3200 4075)(-3200 4125);
WIRE 17 -1 (-3200 4025)(-3200 4075);
WIRE 17 -1 (-3200 3975)(-3200 4025);
WIRE 17 -1 (-3200 3925)(-3200 3975);
WIRE 17 -1 (-1600 3425)(-1600 3475);
WIRE 17 -1 (-1600 3375)(-1600 3425);
WIRE 17 -1 (-1600 3325)(-1600 3375);
WIRE 17 -1 (-1600 3275)(-1600 3325);
WIRE 17 -1 (-1600 3225)(-1600 3275);
WIRE 17 -1 (-1600 3175)(-1600 3225);
WIRE 17 -1 (-1600 3125)(-1600 3175);
WIRE 17 -1 (-1600 3075)(-1600 3125);
WIRE 17 -1 (-1600 3025)(-1600 3075);
WIRE 17 -1 (-1600 2975)(-1600 3025);
WIRE 17 -1 (-1600 2925)(-1600 2975);
WIRE 17 -1 (-1600 2875)(-1600 2925);
WIRE 17 -1 (-1600 2825)(-1600 2875);
WIRE 17 -1 (-1600 2775)(-1600 2825);
WIRE 17 -1 (-1600 2725)(-1600 2775);
WIRE 17 -1 (-1600 2675)(-1600 2725);
WIRE 17 -1 (-1600 2625)(-1600 2675);
WIRE 17 -1 (-1600 2575)(-1600 2625);
WIRE 17 -1 (-1600 2525)(-1600 2575);
WIRE 17 -1 (-1600 2475)(-1600 2525);
WIRE 17 -1 (-1600 2425)(-1600 2475);
WIRE 17 -1 (-1600 2375)(-1600 2425);
WIRE 17 -1 (-1600 2325)(-1600 2375);
WIRE 17 -1 (-1600 2275)(-1600 2325);
WIRE 17 -1 (-1600 2225)(-1600 2275);
WIRE 17 -1 (-1600 2175)(-1600 2225);
WIRE 17 -1 (-1600 2125)(-1600 2175);
WIRE 17 -1 (-1600 2075)(-1600 2125);
WIRE 17 -1 (-1600 2025)(-1600 2075);
WIRE 17 -1 (-1600 1975)(-1600 2025);
WIRE 17 -1 (-1600 1925)(-1600 1975);
WIRE 17 -1 (-1600 1875)(-1600 1925);
WIRE 17 -1 (-1600 1825)(-1600 1875);
WIRE 17 -1 (-1600 1775)(-1600 1825);
WIRE 17 -1 (-1600 1725)(-1600 1775);
WIRE 17 -1 (-1600 1675)(-1600 1725);
WIRE 17 -1 (-1600 1625)(-1600 1675);
WIRE 17 -1 (-3400 3525)(-3400 3425);
WIRE 17 -1 (-3400 3550)(-3400 3525);
WIRE 17 -1 (-3400 3550)(-3800 3550);
FORCEPROP 2 LAST SIG_NAME M_F_CLK_DN<3:0>
J 0
(-3750 3560);
DISPLAY 0.617021 (-3750 3560);
PAINT ORANGE (-3750 3560);
WIRE 17 -1 (-3200 3600)(-3200 3575);
WIRE 17 -1 (-3200 3600)(-3800 3600);
FORCEPROP 2 LAST SIG_NAME M_F_CLK_DP<3:0>
J 0
(-3750 3610);
DISPLAY 0.617021 (-3750 3610);
PAINT ORANGE (-3750 3610);
WIRE 17 -1 (-3200 3475)(-3200 3575);
WIRE 17 -1 (-3200 2975)(-3200 3025);
WIRE 17 -1 (-3200 3050)(-3200 3025);
WIRE 17 -1 (-3200 3050)(-3750 3050);
FORCEPROP 2 LAST SIG_NAME M_F_CKE<3:0>
J 0
(-3725 3060);
DISPLAY 0.617021 (-3725 3060);
PAINT ORANGE (-3725 3060);
WIRE 17 -1 (-3200 3125)(-3200 3175);
WIRE 17 -1 (-3200 3175)(-3200 3225);
WIRE 17 -1 (-3200 3225)(-3200 3275);
WIRE 17 -1 (-3200 3300)(-3200 3275);
WIRE 17 -1 (-3200 3300)(-3750 3300);
FORCEPROP 2 LAST SIG_NAME M_F_CS_N<7:0>
J 0
(-3725 3310);
DISPLAY 0.617021 (-3725 3310);
PAINT ORANGE (-3725 3310);
WIRE 17 -1 (-3200 2900)(-3200 2875);
WIRE 17 -1 (-3200 2900)(-3750 2900);
FORCEPROP 2 LAST SIG_NAME M_F_ODT<3:0>
J 0
(-3725 2910);
DISPLAY 0.617021 (-3725 2910);
PAINT ORANGE (-3725 2910);
WIRE 17 -1 (-3200 2825)(-3200 2875);
WIRE 17 -1 (-3200 2750)(-3200 2725);
WIRE 17 -1 (-3200 2750)(-3750 2750);
FORCEPROP 2 LAST SIG_NAME M_F_ECC<7:0>
J 0
(-3725 2760);
DISPLAY 0.617021 (-3725 2760);
PAINT ORANGE (-3725 2760);
WIRE 17 -1 (-3200 3775)(-3200 3825);
WIRE 17 -1 (-3200 3900)(-3200 3825);
WIRE 17 -1 (-3200 3900)(-3750 3900);
FORCEPROP 2 LAST SIG_NAME M_F_BA<1:0>
J 0
(-3700 3910);
DISPLAY 0.617021 (-3700 3910);
PAINT ORANGE (-3700 3910);
WIRE 17 -1 (-3200 3750)(-3200 3725);
WIRE 17 -1 (-3200 3750)(-3750 3750);
FORCEPROP 2 LAST SIG_NAME M_F_BG<1:0>
J 0
(-3700 3760);
DISPLAY 0.617021 (-3700 3760);
PAINT ORANGE (-3700 3760);
WIRE 17 -1 (-3200 3675)(-3200 3725);
WIRE 17 -1 (-3200 2375)(-3200 2425);
WIRE 17 -1 (-3200 2425)(-3200 2475);
WIRE 17 -1 (-3200 2475)(-3200 2525);
WIRE 17 -1 (-3200 2525)(-3200 2575);
WIRE 17 -1 (-3200 2575)(-3200 2625);
WIRE 17 -1 (-3200 2625)(-3200 2675);
WIRE 17 -1 (-3200 2675)(-3200 2725);
WIRE 16 -1 (-750 1050)(-550 1050);
WIRE 16 -1 (-750 1050)(-750 1100);
WIRE 16 -1 (-750 1100)(-550 1100);
WIRE 16 -1 (-750 1100)(-750 1150);
WIRE 16 -1 (-750 1150)(-550 1150);
WIRE 16 -1 (-750 1150)(-750 1200);
WIRE 16 -1 (-750 1200)(-550 1200);
WIRE 16 -1 (-750 1200)(-750 1250);
WIRE 16 -1 (-750 1250)(-750 1300);
WIRE 16 -1 (-750 1250)(-550 1250);
WIRE 16 -1 (-750 1300)(-550 1300);
WIRE 16 -1 (-750 1300)(-750 1350);
WIRE 16 -1 (-750 1350)(-550 1350);
WIRE 16 -1 (-750 1350)(-750 1400);
WIRE 16 -1 (-750 1400)(-550 1400);
WIRE 16 -1 (-750 1400)(-750 1450);
WIRE 16 -1 (-750 1450)(-550 1450);
WIRE 16 -1 (-750 1450)(-750 1500);
WIRE 16 -1 (-750 1500)(-750 1550);
WIRE 16 -1 (-750 1500)(-550 1500);
WIRE 16 -1 (-750 1550)(-550 1550);
WIRE 16 -1 (-750 1550)(-750 1600);
WIRE 16 -1 (-750 1600)(-550 1600);
WIRE 16 -1 (-750 1600)(-750 1650);
WIRE 16 -1 (-750 1650)(-550 1650);
WIRE 16 -1 (-750 1650)(-750 1700);
WIRE 16 -1 (-750 1700)(-550 1700);
WIRE 16 -1 (-750 1700)(-750 1750);
WIRE 16 -1 (-750 1750)(-750 1800);
WIRE 16 -1 (-750 1750)(-550 1750);
WIRE 16 -1 (-750 1800)(-550 1800);
WIRE 16 -1 (-750 1800)(-750 1850);
WIRE 16 -1 (-750 1850)(-550 1850);
WIRE 16 -1 (-750 1850)(-750 1900);
WIRE 16 -1 (-750 1900)(-550 1900);
WIRE 16 -1 (-750 1900)(-750 1950);
WIRE 16 -1 (-750 1950)(-550 1950);
WIRE 16 -1 (-750 1950)(-750 2000);
WIRE 16 -1 (-750 2000)(-750 2050);
WIRE 16 -1 (-750 2000)(-550 2000);
WIRE 16 -1 (-750 2050)(-550 2050);
WIRE 16 -1 (-750 2050)(-750 2100);
WIRE 16 -1 (-750 2100)(-550 2100);
WIRE 16 -1 (-750 2100)(-750 2150);
WIRE 16 -1 (-750 2150)(-550 2150);
WIRE 16 -1 (-750 2150)(-750 2200);
WIRE 16 -1 (-750 2200)(-550 2200);
WIRE 16 -1 (-750 2200)(-750 2250);
WIRE 16 -1 (-750 2250)(-550 2250);
WIRE 16 -1 (-750 2250)(-750 2300);
WIRE 16 -1 (-750 2300)(-550 2300);
WIRE 16 -1 (-1150 2300)(-750 2300);
WIRE 16 -1 (-1150 2425)(-1150 2300);
WIRE 16 -1 (-550 2400)(-750 2400);
WIRE 16 -1 (-750 2400)(-750 2450);
WIRE 16 -1 (-750 2450)(-550 2450);
WIRE 16 -1 (-900 2450)(-750 2450);
WIRE 16 -1 (-900 2550)(-900 2450);
WIRE 16 -1 (2500 3650)(2500 3700);
WIRE 16 -1 (2500 3600)(2500 3650);
WIRE 16 -1 (2500 3650)(2300 3650);
WIRE 16 -1 (2500 3700)(2300 3700);
WIRE 16 -1 (2500 3600)(2300 3600);
WIRE 16 -1 (2500 3550)(2500 3600);
WIRE 16 -1 (2500 3500)(2500 3550);
WIRE 16 -1 (2500 3550)(2300 3550);
WIRE 16 -1 (2500 3450)(2500 3500);
WIRE 16 -1 (2500 3500)(2300 3500);
WIRE 16 -1 (2500 3400)(2500 3450);
WIRE 16 -1 (2500 3450)(2300 3450);
WIRE 16 -1 (2500 3350)(2500 3400);
WIRE 16 -1 (2500 3400)(2300 3400);
WIRE 16 -1 (2500 3300)(2500 3350);
WIRE 16 -1 (2500 3350)(2300 3350);
WIRE 16 -1 (2500 3250)(2500 3300);
WIRE 16 -1 (2500 3300)(2300 3300);
WIRE 16 -1 (2500 3200)(2500 3250);
WIRE 16 -1 (2500 3250)(2300 3250);
WIRE 16 -1 (2500 3150)(2500 3200);
WIRE 16 -1 (2500 3200)(2300 3200);
WIRE 16 -1 (2500 3100)(2500 3150);
WIRE 16 -1 (2500 3150)(2300 3150);
WIRE 16 -1 (2500 3100)(2300 3100);
WIRE 16 -1 (2500 3050)(2500 3100);
WIRE 16 -1 (2500 3000)(2500 3050);
WIRE 16 -1 (2500 3050)(2300 3050);
WIRE 16 -1 (2500 2950)(2500 3000);
WIRE 16 -1 (2500 3000)(2300 3000);
WIRE 16 -1 (2500 2900)(2500 2950);
WIRE 16 -1 (2500 2950)(2300 2950);
WIRE 16 -1 (2500 2850)(2500 2900);
WIRE 16 -1 (2500 2900)(2300 2900);
WIRE 16 -1 (2500 2800)(2500 2850);
WIRE 16 -1 (2500 2850)(2300 2850);
WIRE 16 -1 (2500 2750)(2500 2800);
WIRE 16 -1 (2500 2800)(2300 2800);
WIRE 16 -1 (2500 2700)(2500 2750);
WIRE 16 -1 (2500 2750)(2300 2750);
WIRE 16 -1 (2500 2650)(2500 2700);
WIRE 16 -1 (2500 2700)(2300 2700);
WIRE 16 -1 (2500 2600)(2500 2650);
WIRE 16 -1 (2500 2650)(2300 2650);
WIRE 16 -1 (2500 2600)(2300 2600);
WIRE 16 -1 (2500 2550)(2500 2600);
WIRE 16 -1 (2500 2500)(2500 2550);
WIRE 16 -1 (2500 2550)(2300 2550);
WIRE 16 -1 (2500 2450)(2500 2500);
WIRE 16 -1 (2500 2500)(2300 2500);
WIRE 16 -1 (2500 2400)(2500 2450);
WIRE 16 -1 (2500 2450)(2300 2450);
WIRE 16 -1 (2500 2350)(2500 2400);
WIRE 16 -1 (2500 2400)(2300 2400);
WIRE 16 -1 (2500 2300)(2500 2350);
WIRE 16 -1 (2500 2350)(2300 2350);
WIRE 16 -1 (2500 2250)(2500 2300);
WIRE 16 -1 (2500 2300)(2300 2300);
WIRE 16 -1 (2500 2200)(2500 2250);
WIRE 16 -1 (2500 2250)(2300 2250);
WIRE 16 -1 (2500 2150)(2500 2200);
WIRE 16 -1 (2500 2200)(2300 2200);
WIRE 16 -1 (2500 2100)(2500 2150);
WIRE 16 -1 (2500 2150)(2300 2150);
WIRE 16 -1 (2500 2050)(2500 2100);
WIRE 16 -1 (2500 2100)(2300 2100);
WIRE 16 -1 (2500 2050)(2300 2050);
WIRE 16 -1 (2500 2000)(2500 2050);
WIRE 16 -1 (2500 1950)(2500 2000);
WIRE 16 -1 (2500 2000)(2300 2000);
WIRE 16 -1 (2500 1900)(2500 1950);
WIRE 16 -1 (2500 1950)(2300 1950);
WIRE 16 -1 (2500 1850)(2500 1900);
WIRE 16 -1 (2500 1900)(2300 1900);
WIRE 16 -1 (2500 1800)(2500 1850);
WIRE 16 -1 (2500 1850)(2300 1850);
WIRE 16 -1 (2500 1750)(2500 1800);
WIRE 16 -1 (2500 1800)(2300 1800);
WIRE 16 -1 (2500 1700)(2500 1750);
WIRE 16 -1 (2500 1750)(2300 1750);
WIRE 16 -1 (2500 1650)(2500 1700);
WIRE 16 -1 (2500 1700)(2300 1700);
WIRE 16 -1 (2500 1600)(2500 1650);
WIRE 16 -1 (2500 1650)(2300 1650);
WIRE 16 -1 (2500 1550)(2500 1600);
WIRE 16 -1 (2500 1600)(2300 1600);
WIRE 16 -1 (2500 1550)(2300 1550);
WIRE 16 -1 (2500 1500)(2500 1550);
WIRE 16 -1 (2500 1450)(2500 1500);
WIRE 16 -1 (2500 1500)(2300 1500);
WIRE 16 -1 (2500 1400)(2500 1450);
WIRE 16 -1 (2500 1450)(2300 1450);
WIRE 16 -1 (2500 1300)(2500 1400);
WIRE 16 -1 (2500 1400)(2300 1400);
WIRE 16 -1 (-4600 1300)(-4600 1200);
WIRE 16 -1 (-750 2550)(-750 2600);
WIRE 16 -1 (-750 2550)(-550 2550);
WIRE 16 -1 (-750 2600)(-550 2600);
WIRE 16 -1 (-750 2600)(-750 2650);
WIRE 16 -1 (-750 2650)(-550 2650);
WIRE 16 -1 (-750 2650)(-750 2700);
WIRE 16 -1 (-750 2700)(-550 2700);
WIRE 16 -1 (-750 2700)(-750 2750);
WIRE 16 -1 (-750 2850)(-750 2750);
WIRE 16 -1 (-750 2750)(-550 2750);
WIRE 16 -1 (-2900 1800)(-3100 1800);
WIRE 16 -1 (-3100 1800)(-3100 1900);
WIRE 16 -1 (-3100 1900)(-2900 1900);
WIRE 16 -1 (-3100 1900)(-3100 1950);
WIRE 16 -1 (-2900 1950)(-3100 1950);
WIRE 16 -1 (-3100 1950)(-5200 1950);
WIRE 16 -1 (-5200 1950)(-5200 2050);
WIRE 16 -1 (-2900 1850)(-5200 1850);
WIRE 16 -1 (-5200 1850)(-5200 1800);
WIRE 16 -1 (450 2700)(650 2700);
WIRE 16 -1 (650 2700)(650 2750);
WIRE 16 -1 (450 2750)(650 2750);
WIRE 16 -1 (650 2750)(650 2925);
WIRE 16 -1 (1100 3700)(1300 3700);
WIRE 16 -1 (1100 3650)(1100 3700);
WIRE 16 -1 (1100 3650)(1300 3650);
WIRE 16 -1 (1100 3600)(1100 3650);
WIRE 16 -1 (1100 3600)(1300 3600);
WIRE 16 -1 (1100 3550)(1100 3600);
WIRE 16 -1 (1100 3550)(1300 3550);
WIRE 16 -1 (1100 3500)(1100 3550);
WIRE 16 -1 (1100 3500)(1300 3500);
WIRE 16 -1 (1100 3450)(1100 3500);
WIRE 16 -1 (1100 3450)(1300 3450);
WIRE 16 -1 (1100 3400)(1100 3450);
WIRE 16 -1 (1100 3400)(1300 3400);
WIRE 16 -1 (1100 3350)(1100 3400);
WIRE 16 -1 (1100 3350)(1300 3350);
WIRE 16 -1 (1100 3300)(1100 3350);
WIRE 16 -1 (1100 3300)(1300 3300);
WIRE 16 -1 (1100 3250)(1100 3300);
WIRE 16 -1 (1100 3250)(1300 3250);
WIRE 16 -1 (1100 3200)(1100 3250);
WIRE 16 -1 (1100 3200)(1300 3200);
WIRE 16 -1 (1100 3150)(1100 3200);
WIRE 16 -1 (1100 3150)(1300 3150);
WIRE 16 -1 (1100 3100)(1100 3150);
WIRE 16 -1 (1100 3100)(1300 3100);
WIRE 16 -1 (1100 3050)(1100 3100);
WIRE 16 -1 (1100 3050)(1300 3050);
WIRE 16 -1 (1100 3000)(1100 3050);
WIRE 16 -1 (1100 3000)(1300 3000);
WIRE 16 -1 (1100 2950)(1100 3000);
WIRE 16 -1 (1100 2950)(1300 2950);
WIRE 16 -1 (1100 2900)(1100 2950);
WIRE 16 -1 (1100 2900)(1300 2900);
WIRE 16 -1 (1100 2850)(1100 2900);
WIRE 16 -1 (1100 2850)(1300 2850);
WIRE 16 -1 (1100 2800)(1100 2850);
WIRE 16 -1 (1100 2800)(1300 2800);
WIRE 16 -1 (1100 2750)(1100 2800);
WIRE 16 -1 (1100 2750)(1300 2750);
WIRE 16 -1 (1100 2700)(1100 2750);
WIRE 16 -1 (1100 2700)(1300 2700);
WIRE 16 -1 (1100 2650)(1100 2700);
WIRE 16 -1 (1100 2650)(1300 2650);
WIRE 16 -1 (1100 2600)(1100 2650);
WIRE 16 -1 (1100 2600)(1300 2600);
WIRE 16 -1 (1100 2550)(1100 2600);
WIRE 16 -1 (1100 2550)(1300 2550);
WIRE 16 -1 (1100 2500)(1100 2550);
WIRE 16 -1 (1100 2500)(1300 2500);
WIRE 16 -1 (1100 2450)(1100 2500);
WIRE 16 -1 (1100 2450)(1300 2450);
WIRE 16 -1 (1100 2400)(1100 2450);
WIRE 16 -1 (1100 2400)(1300 2400);
WIRE 16 -1 (1100 2350)(1100 2400);
WIRE 16 -1 (1100 2350)(1300 2350);
WIRE 16 -1 (1100 2300)(1100 2350);
WIRE 16 -1 (1100 2300)(1300 2300);
WIRE 16 -1 (1100 2250)(1100 2300);
WIRE 16 -1 (1100 2250)(1300 2250);
WIRE 16 -1 (1100 2200)(1100 2250);
WIRE 16 -1 (1100 2200)(1300 2200);
WIRE 16 -1 (1100 2150)(1100 2200);
WIRE 16 -1 (1100 2150)(1300 2150);
WIRE 16 -1 (1100 2100)(1100 2150);
WIRE 16 -1 (1100 2100)(1300 2100);
WIRE 16 -1 (1100 2050)(1100 2100);
WIRE 16 -1 (1100 2050)(1300 2050);
WIRE 16 -1 (1100 2000)(1100 2050);
WIRE 16 -1 (1100 2000)(1300 2000);
WIRE 16 -1 (1100 1950)(1100 2000);
WIRE 16 -1 (1100 1950)(1300 1950);
WIRE 16 -1 (1100 1900)(1100 1950);
WIRE 16 -1 (1100 1900)(1300 1900);
WIRE 16 -1 (1100 1850)(1100 1900);
WIRE 16 -1 (1100 1850)(1300 1850);
WIRE 16 -1 (1100 1800)(1100 1850);
WIRE 16 -1 (1100 1800)(1300 1800);
WIRE 16 -1 (1100 1750)(1100 1800);
WIRE 16 -1 (1100 1750)(1300 1750);
WIRE 16 -1 (1100 1700)(1100 1750);
WIRE 16 -1 (1100 1700)(1300 1700);
WIRE 16 -1 (1100 1650)(1100 1700);
WIRE 16 -1 (1100 1650)(1300 1650);
WIRE 16 -1 (1100 1600)(1100 1650);
WIRE 16 -1 (1100 1600)(1300 1600);
WIRE 16 -1 (1100 1550)(1100 1600);
WIRE 16 -1 (1100 1550)(1300 1550);
WIRE 16 -1 (1100 1500)(1100 1550);
WIRE 16 -1 (1100 1500)(1300 1500);
WIRE 16 -1 (1100 1450)(1100 1500);
WIRE 16 -1 (1100 1450)(1300 1450);
WIRE 16 -1 (1100 1400)(1100 1450);
WIRE 16 -1 (1100 1400)(1300 1400);
WIRE 16 -1 (1100 1300)(1100 1400);
WIRE 16 -1 (-2900 1600)(-4600 1600);
FORCEPROP 2 LAST SIG_NAME M_F_VREF
J 0
(-3700 1610);
DISPLAY 0.617021 (-3700 1610);
PAINT ORANGE (-3700 1610);
WIRE 16 -1 (-4600 1600)(-4600 1500);
WIRE 16 -1 (-4700 1600)(-4600 1600);
WIRE 16 -1 (-3750 1500)(-2900 1500);
FORCEPROP 2 LAST SIG_NAME TP_CH_F_DIMM_F1_RFU_2
J 0
(-3700 1510);
DISPLAY 0.617021 (-3700 1510);
PAINT ORANGE (-3700 1510);
FORCEPROP 2 LASTPROP $XRERR UNIQUE?
J 0
(-3990 1500);
DISPLAY 0.638298 (-3990 1500);
PAINT MONO (-3990 1500);
DISPLAY INVISIBLE (-3990 1500);
WIRE 16 -1 (-3750 1400)(-2900 1400);
FORCEPROP 2 LAST SIG_NAME TP_CH_F_DIMM_F1_RFU_0
J 0
(-3700 1410);
DISPLAY 0.617021 (-3700 1410);
PAINT ORANGE (-3700 1410);
FORCEPROP 2 LASTPROP $XRERR UNIQUE?
J 0
(-3990 1400);
DISPLAY 0.638298 (-3990 1400);
PAINT MONO (-3990 1400);
DISPLAY INVISIBLE (-3990 1400);
WIRE 16 -1 (-3750 1450)(-2900 1450);
FORCEPROP 2 LAST SIG_NAME TP_CH_F_DIMM_F1_RFU_1
J 0
(-3700 1460);
DISPLAY 0.617021 (-3700 1460);
PAINT ORANGE (-3700 1460);
FORCEPROP 2 LASTPROP $XRERR UNIQUE?
J 0
(-3990 1450);
DISPLAY 0.638298 (-3990 1450);
PAINT MONO (-3990 1450);
DISPLAY INVISIBLE (-3990 1450);
WIRE 16 -1 (-3750 1700)(-2900 1700);
FORCEPROP 2 LAST SIG_NAME SMB_DDR_DEF_VPP_SCL
J 0
(-3710 1710);
DISPLAY 0.617021 (-3710 1710);
PAINT ORANGE (-3710 1710);
WIRE 16 -1 (-3750 1750)(-2900 1750);
FORCEPROP 2 LAST SIG_NAME SMB_DDR_DEF_VPP_SDA
J 0
(-3710 1760);
DISPLAY 0.617021 (-3710 1760);
PAINT ORANGE (-3710 1760);
WIRE 16 -1 (-3750 1300)(-2900 1300);
FORCEPROP 2 LAST SIG_NAME FM_ADR_COMPLETE_DEF_N
J 0
(-3700 1310);
DISPLAY 0.617021 (-3700 1310);
PAINT ORANGE (-3700 1310);
WIRE 16 -1 (-3350 2150)(-2900 2150);
WIRE 16 -1 (-3350 2400)(-3350 2150);
WIRE 16 -1 (-3350 2400)(-4075 2400);
FORCEPROP 2 LAST SIG_NAME FM_DIMM_EVENT_COD_N
J 0
(-4007 2400);
DISPLAY 0.617021 (-4007 2400);
PAINT ORANGE (-4007 2400);
WIRE 16 -1 (-2900 2250)(-3250 2250);
WIRE 16 -1 (-3250 2250)(-3250 2700);
WIRE 16 -1 (-3250 2700)(-3750 2700);
FORCEPROP 2 LAST SIG_NAME M_F_PAR
J 0
(-3725 2710);
DISPLAY 0.617021 (-3725 2710);
PAINT ORANGE (-3725 2710);
WIRE 16 -1 (-2900 2200)(-3300 2200);
WIRE 16 -1 (-3300 2200)(-3300 2650);
WIRE 16 -1 (-3300 2650)(-3750 2650);
FORCEPROP 2 LAST SIG_NAME M_DEF_RST_N
J 0
(-3725 2660);
DISPLAY 0.617021 (-3725 2660);
PAINT ORANGE (-3725 2660);
WIRE 16 -1 (-2900 3800)(-3100 3800);
WIRE 16 -1 (-2900 3250)(-3100 3250);
WIRE 16 -1 (-2900 3200)(-3100 3200);
WIRE 16 -1 (-2900 3150)(-3100 3150);
WIRE 16 -1 (-2900 3900)(-3100 3900);
WIRE 16 -1 (-2900 3950)(-3100 3950);
WIRE 16 -1 (-2900 4050)(-3100 4050);
WIRE 16 -1 (-2900 2650)(-3100 2650);
WIRE 16 -1 (-2900 2600)(-3100 2600);
WIRE 16 -1 (-2900 2550)(-3100 2550);
WIRE 16 -1 (-2900 2500)(-3100 2500);
WIRE 16 -1 (-2900 2450)(-3100 2450);
WIRE 16 -1 (-2900 2400)(-3100 2400);
WIRE 16 -1 (-2900 2350)(-3100 2350);
WIRE 16 -1 (-2900 3000)(-3100 3000);
WIRE 16 -1 (-2900 3650)(-3100 3650);
WIRE 16 -1 (-2900 3700)(-3100 3700);
WIRE 16 -1 (-2900 3750)(-3100 3750);
WIRE 16 -1 (-2900 4000)(-3100 4000);
WIRE 16 -1 (-2900 2700)(-3100 2700);
WIRE 16 -1 (-2900 2800)(-3100 2800);
WIRE 16 -1 (-2900 2850)(-3100 2850);
WIRE 16 -1 (-2900 3100)(-3100 3100);
WIRE 16 -1 (-2900 2950)(-3100 2950);
WIRE 16 -1 (-2900 3450)(-3100 3450);
WIRE 16 -1 (-2900 3550)(-3100 3550);
WIRE 16 -1 (-2900 3500)(-3300 3500);
WIRE 16 -1 (-2900 3400)(-3300 3400);
WIRE 16 -1 (-2900 2050)(-3900 2050);
FORCEPROP 2 LAST SIG_NAME M_F_ACT_N
J 0
(-3875 2060);
DISPLAY 0.617021 (-3875 2060);
PAINT ORANGE (-3875 2060);
WIRE 16 -1 (-2900 2100)(-3925 2100);
FORCEPROP 2 LAST SIG_NAME M_F_ALERT_N
J 0
(-3875 2110);
DISPLAY 0.617021 (-3875 2110);
PAINT ORANGE (-3875 2110);
WIRE 16 -1 (-3050 3350)(-3050 3300);
WIRE 16 -1 (-3050 3350)(-3750 3350);
FORCEPROP 2 LAST SIG_NAME M_F_C<2>
J 0
(-3725 3360);
DISPLAY 0.617021 (-3725 3360);
PAINT ORANGE (-3725 3360);
WIRE 16 -1 (-3050 3300)(-2900 3300);
WIRE 16 -1 (-1700 2000)(-1900 2000);
WIRE 16 -1 (-1700 1950)(-1900 1950);
WIRE 16 -1 (-1700 1900)(-1900 1900);
WIRE 16 -1 (-1700 1650)(-1900 1650);
WIRE 16 -1 (-1700 1600)(-1900 1600);
WIRE 16 -1 (-1700 1700)(-1900 1700);
WIRE 16 -1 (-1700 1750)(-1900 1750);
WIRE 16 -1 (-1700 1800)(-1900 1800);
WIRE 16 -1 (-1700 1850)(-1900 1850);
WIRE 16 -1 (-1700 2550)(-1900 2550);
WIRE 16 -1 (-1700 2500)(-1900 2500);
WIRE 16 -1 (-1700 2400)(-1900 2400);
WIRE 16 -1 (-1700 2300)(-1900 2300);
WIRE 16 -1 (-1700 2250)(-1900 2250);
WIRE 16 -1 (-1700 2200)(-1900 2200);
WIRE 16 -1 (-1700 2150)(-1900 2150);
WIRE 16 -1 (-1700 2050)(-1900 2050);
WIRE 16 -1 (-1700 2350)(-1900 2350);
WIRE 16 -1 (-1700 2450)(-1900 2450);
WIRE 16 -1 (-1700 2100)(-1900 2100);
WIRE 16 -1 (-1700 3050)(-1900 3050);
WIRE 16 -1 (-1700 3000)(-1900 3000);
WIRE 16 -1 (-1700 2850)(-1900 2850);
WIRE 16 -1 (-1700 2800)(-1900 2800);
WIRE 16 -1 (-1700 2750)(-1900 2750);
WIRE 16 -1 (-1700 2700)(-1900 2700);
WIRE 16 -1 (-1700 2650)(-1900 2650);
WIRE 16 -1 (-1700 2600)(-1900 2600);
WIRE 16 -1 (-1700 2950)(-1900 2950);
WIRE 16 -1 (-1700 2900)(-1900 2900);
WIRE 16 -1 (-1700 3550)(-1900 3550);
WIRE 16 -1 (-1700 3450)(-1900 3450);
WIRE 16 -1 (-1700 3300)(-1900 3300);
WIRE 16 -1 (-1700 3250)(-1900 3250);
WIRE 16 -1 (-1700 3200)(-1900 3200);
WIRE 16 -1 (-1700 3150)(-1900 3150);
WIRE 16 -1 (-1700 3100)(-1900 3100);
WIRE 16 -1 (-1700 3350)(-1900 3350);
WIRE 16 -1 (-1700 3400)(-1900 3400);
WIRE 16 -1 (-1700 3500)(-1900 3500);
WIRE 16 -1 (-1700 3900)(-1900 3900);
WIRE 16 -1 (-1700 3850)(-1900 3850);
WIRE 16 -1 (-1700 3800)(-1900 3800);
WIRE 16 -1 (-1700 3750)(-1900 3750);
WIRE 16 -1 (-1700 3700)(-1900 3700);
WIRE 16 -1 (-1700 3650)(-1900 3650);
WIRE 16 -1 (-1700 3600)(-1900 3600);
WIRE 16 -1 (-1700 4050)(-1900 4050);
WIRE 16 -1 (-1700 4000)(-1900 4000);
WIRE 16 -1 (-1700 3950)(-1900 3950);
WIRE 16 -1 (-2900 4500)(-3100 4500);
WIRE 16 -1 (-2900 4550)(-3100 4550);
WIRE 16 -1 (-2900 4750)(-3100 4750);
WIRE 16 -1 (-2900 4100)(-3100 4100);
WIRE 16 -1 (-2900 4150)(-3100 4150);
WIRE 16 -1 (-2900 4200)(-3100 4200);
WIRE 16 -1 (-2900 4250)(-3100 4250);
WIRE 16 -1 (-2900 4300)(-3100 4300);
WIRE 16 -1 (-2900 4350)(-3100 4350);
WIRE 16 -1 (-2900 4400)(-3100 4400);
WIRE 16 -1 (-2900 4450)(-3100 4450);
WIRE 16 -1 (-2900 4600)(-3100 4600);
WIRE 16 -1 (-2900 4650)(-3100 4650);
WIRE 16 -1 (-2900 4700)(-3100 4700);
WIRE 16 -1 (-1700 4600)(-1900 4600);
WIRE 16 -1 (-1700 4550)(-1900 4550);
WIRE 16 -1 (-1700 4400)(-1900 4400);
WIRE 16 -1 (-1700 4350)(-1900 4350);
WIRE 16 -1 (-1700 4450)(-1900 4450);
WIRE 16 -1 (-1700 4500)(-1900 4500);
WIRE 16 -1 (-1700 4300)(-1900 4300);
WIRE 16 -1 (-1700 4250)(-1900 4250);
WIRE 16 -1 (-1700 4200)(-1900 4200);
WIRE 16 -1 (-1700 4150)(-1900 4150);
WIRE 16 -1 (-1700 4100)(-1900 4100);
WIRE 16 -1 (-1700 4750)(-1900 4750);
WIRE 16 -1 (-1700 4700)(-1900 4700);
WIRE 16 -1 (-1700 4650)(-1900 4650);
WIRE 16 -1 (850 3400)(450 3400);
WIRE 16 -1 (650 3450)(450 3450);
WIRE 16 -1 (850 3500)(450 3500);
WIRE 16 -1 (650 3550)(450 3550);
WIRE 16 -1 (850 3600)(450 3600);
WIRE 16 -1 (650 3650)(450 3650);
WIRE 16 -1 (850 3700)(450 3700);
WIRE 16 -1 (650 3750)(450 3750);
WIRE 16 -1 (850 3800)(450 3800);
WIRE 16 -1 (650 3850)(450 3850);
WIRE 16 -1 (850 3900)(450 3900);
WIRE 16 -1 (650 3950)(450 3950);
WIRE 16 -1 (850 4000)(450 4000);
WIRE 16 -1 (650 4050)(450 4050);
WIRE 16 -1 (850 4400)(450 4400);
WIRE 16 -1 (650 4450)(450 4450);
WIRE 16 -1 (850 4500)(450 4500);
WIRE 16 -1 (650 4550)(450 4550);
WIRE 16 -1 (850 4600)(450 4600);
WIRE 16 -1 (650 4650)(450 4650);
WIRE 16 -1 (850 4700)(450 4700);
WIRE 16 -1 (650 4750)(450 4750);
WIRE 16 -1 (850 4800)(450 4800);
WIRE 16 -1 (650 4850)(450 4850);
WIRE 16 -1 (850 4900)(450 4900);
WIRE 16 -1 (650 4950)(450 4950);
WIRE 16 -1 (850 5000)(450 5000);
WIRE 16 -1 (650 5050)(450 5050);
WIRE 16 -1 (850 5100)(450 5100);
WIRE 16 -1 (850 4100)(450 4100);
WIRE 16 -1 (650 4150)(450 4150);
WIRE 16 -1 (850 4200)(450 4200);
WIRE 16 -1 (650 4250)(450 4250);
WIRE 16 -1 (850 4300)(450 4300);
WIRE 16 -1 (650 4350)(450 4350);
WIRE 16 -1 (650 5150)(450 5150);
DOT 1 (-750 2600);
DOT 1 (-750 2750);
DOT 1 (1100 3000);
DOT 1 (650 2750);
DOT 1 (-750 1250);
DOT 1 (-750 2300);
DOT 1 (-750 2150);
DOT 1 (-750 2450);
DOT 1 (-750 1150);
DOT 1 (-750 1100);
DOT 1 (-750 1200);
DOT 1 (-750 1400);
DOT 1 (-750 1350);
DOT 1 (-750 1500);
DOT 1 (-750 1550);
DOT 1 (-750 1650);
DOT 1 (-750 1600);
DOT 1 (-750 1700);
DOT 1 (-750 1800);
DOT 1 (-750 1750);
DOT 1 (-750 1900);
DOT 1 (-750 1850);
DOT 1 (-750 1950);
DOT 1 (-750 2050);
DOT 1 (-750 2000);
DOT 1 (-750 2200);
DOT 1 (-750 2100);
DOT 1 (-750 2250);
DOT 1 (-750 2700);
DOT 1 (-750 2650);
DOT 1 (2500 3650);
DOT 1 (2500 3600);
DOT 1 (2500 3550);
DOT 1 (2500 3500);
DOT 1 (2500 3450);
DOT 1 (2500 3400);
DOT 1 (2500 3350);
DOT 1 (2500 3300);
DOT 1 (2500 3250);
DOT 1 (2500 3200);
DOT 1 (2500 3150);
DOT 1 (2500 3100);
DOT 1 (2500 3050);
DOT 1 (2500 3000);
DOT 1 (2500 2950);
DOT 1 (2500 2900);
DOT 1 (2500 2850);
DOT 1 (2500 2800);
DOT 1 (2500 2750);
DOT 1 (2500 2700);
DOT 1 (2500 2650);
DOT 1 (2500 2600);
DOT 1 (2500 2550);
DOT 1 (2500 2500);
DOT 1 (2500 2450);
DOT 1 (2500 2400);
DOT 1 (2500 2350);
DOT 1 (2500 2300);
DOT 1 (2500 2250);
DOT 1 (2500 2200);
DOT 1 (2500 2100);
DOT 1 (2500 2150);
DOT 1 (2500 2050);
DOT 1 (2500 2000);
DOT 1 (2500 1950);
DOT 1 (2500 1900);
DOT 1 (2500 1850);
DOT 1 (2500 1800);
DOT 1 (2500 1750);
DOT 1 (2500 1700);
DOT 1 (2500 1650);
DOT 1 (2500 1600);
DOT 1 (2500 1550);
DOT 1 (2500 1500);
DOT 1 (2500 1450);
DOT 1 (2500 1400);
DOT 1 (1100 3650);
DOT 1 (1100 3600);
DOT 1 (1100 3550);
DOT 1 (1100 3500);
DOT 1 (1100 3400);
DOT 1 (1100 3450);
DOT 1 (1100 3250);
DOT 1 (1100 3350);
DOT 1 (1100 3300);
DOT 1 (1100 3200);
DOT 1 (1100 3150);
DOT 1 (1100 3100);
DOT 1 (1100 3050);
DOT 1 (1100 2950);
DOT 1 (1100 2850);
DOT 1 (1100 2750);
DOT 1 (1100 2700);
DOT 1 (1100 2650);
DOT 1 (1100 2600);
DOT 1 (1100 2500);
DOT 1 (1100 2550);
DOT 1 (1100 2450);
DOT 1 (1100 2400);
DOT 1 (1100 2350);
DOT 1 (1100 2300);
DOT 1 (1100 2250);
DOT 1 (1100 2200);
DOT 1 (1100 2100);
DOT 1 (1100 2150);
DOT 1 (1100 2050);
DOT 1 (1100 2000);
DOT 1 (1100 1950);
DOT 1 (1100 1850);
DOT 1 (1100 1800);
DOT 1 (1100 1700);
DOT 1 (1100 1750);
DOT 1 (1100 1600);
DOT 1 (1100 1650);
DOT 1 (1100 1500);
DOT 1 (1100 1450);
DOT 1 (1100 1400);
DOT 1 (-750 1450);
DOT 1 (-750 1300);
DOT 1 (1100 1550);
DOT 1 (1100 1900);
DOT 1 (-3100 1900);
DOT 1 (-3100 1950);
DOT 1 (-4600 1600);
DOT 1 (1100 2800);
DOT 1 (1100 2900);
FORCENOTE
PLACE CAP NEAR DIMM CONNECTOR
(-5288 1052) 0;
DISPLAY LEFT (-5288 1052);
DISPLAY 1.595745 (-5288 1052);
PAINT PURPLE (-5288 1052);
FORCENOTE
SMBUS ADDR: 0XAA
(-5275 759) 0;
DISPLAY LEFT (-5275 759);
DISPLAY 1.957447 (-5275 759);
PAINT PURPLE (-5275 759);
QUIT
